FILE_TYPE = MACRO_DRAWING;
SET COLOR_WIRE YELLOW;
SET COLOR_PROP ORANGE;
SET COLOR_DOT WHITE;
SET COLOR_ARC YELLOW;
SET COLOR_BODY GREEN;
SET COLOR_NOTE PURPLE;
SET PROP_DISPLAY VALUE;
SET PAGE_NUMBER P96;
FORCEADD UNIVERSAL_GND..1
(-2275 -400);
FORCEPROP 3 LASTPIN (-2275 -350) SIG_NAME GND\g
J 0
(-2265 -340);
DISPLAY 0.659574 (-2265 -340);
PAINT MONO (-2265 -340);
DISPLAY INVISIBLE (-2265 -340);
FORCEPROP 2 LAST CDS_LIB logical_power
J 0
(-2275 -400);
PAINT MONO (-2275 -400);
DISPLAY INVISIBLE (-2275 -400);
FORCEPROP 1 LAST HDL_POWER GND
J 1
(-2250 -475);
DISPLAY 0.872340 (-2250 -475);
PAINT GREEN (-2250 -475);
DISPLAY INVISIBLE (-2250 -475);
FORCEPROP 1 LAST PATH I1
J 0
(-2200 -400);
DISPLAY 0.872340 (-2200 -400);
PAINT AQUA (-2200 -400);
DISPLAY INVISIBLE (-2200 -400);
FORCEADD OFFPAGE..1
(-3425 1725);
FORCEPROP 2 LAST $XR3 97 
J 0
(-3677 1689);
DISPLAY 0.638298 (-3677 1689);
PAINT MONO (-3677 1689);
FORCEPROP 2 LAST $XR2 95 
J 0
(-3857 1725);
DISPLAY 0.638298 (-3857 1725);
PAINT MONO (-3857 1725);
FORCEPROP 2 LAST $XR1 94 
J 0
(-3767 1725);
DISPLAY 0.638298 (-3767 1725);
PAINT MONO (-3767 1725);
FORCEPROP 2 LAST $XR0 129 
J 0
(-3677 1725);
DISPLAY 0.638298 (-3677 1725);
PAINT MONO (-3677 1725);
FORCEPROP 2 LAST CDS_LIB standard
J 0
(-3425 1725);
PAINT MONO (-3425 1725);
DISPLAY INVISIBLE (-3425 1725);
FORCEPROP 1 LAST OFFPAGE TRUE
J 0
(-3100 1600);
DISPLAY 0.872340 (-3100 1600);
DISPLAY INVISIBLE (-3100 1600);
FORCEPROP 1 LAST COMMENT_BODY TRUE
J 0
(-3300 1625);
DISPLAY 0.872340 (-3300 1625);
PAINT GREEN (-3300 1625);
DISPLAY INVISIBLE (-3300 1625);
FORCEPROP 2 LAST PATH I10
J 0
(-3375 1800);
DISPLAY 1.021277 (-3375 1800);
DISPLAY INVISIBLE (-3375 1800);
FORCEADD TAP..1
(-850 3425);
FORCEPROP 3 LASTPIN (-900 3425) SIG_NAME M_H_CPU0_SA_DQ<20>
J 0
(-890 3435);
DISPLAY 0.659574 (-890 3435);
PAINT MONO (-890 3435);
DISPLAY INVISIBLE (-890 3435);
FORCEPROP 1 LASTPIN (-900 3425) BN 20
J 0
(-912 3433);
DISPLAY 0.680851 (-912 3433);
PAINT GREEN (-912 3433);
FORCEPROP 2 LAST CDS_LIB standard
J 0
(-850 3425);
PAINT MONO (-850 3425);
DISPLAY INVISIBLE (-850 3425);
FORCEPROP 1 LAST BODY_TYPE PLUMBING
J 0
(-850 3475);
DISPLAY 0.872340 (-850 3475);
PAINT GREEN (-850 3475);
DISPLAY INVISIBLE (-850 3475);
FORCEPROP 1 LAST HDL_TAP TRUE
J 0
(-525 3300);
DISPLAY 0.872340 (-525 3300);
DISPLAY INVISIBLE (-525 3300);
FORCEPROP 1 LAST PATH I100
J 0
(-852 3425);
DISPLAY 0.872340 (-852 3425);
PAINT GREEN (-852 3425);
DISPLAY INVISIBLE (-852 3425);
FORCEADD TAP..1
(-850 3375);
FORCEPROP 3 LASTPIN (-900 3375) SIG_NAME M_H_CPU0_SA_DQ<19>
J 0
(-890 3385);
DISPLAY 0.659574 (-890 3385);
PAINT MONO (-890 3385);
DISPLAY INVISIBLE (-890 3385);
FORCEPROP 1 LASTPIN (-900 3375) BN 19
J 0
(-912 3383);
DISPLAY 0.680851 (-912 3383);
PAINT GREEN (-912 3383);
FORCEPROP 2 LAST CDS_LIB standard
J 0
(-850 3375);
PAINT MONO (-850 3375);
DISPLAY INVISIBLE (-850 3375);
FORCEPROP 1 LAST BODY_TYPE PLUMBING
J 0
(-850 3425);
DISPLAY 0.872340 (-850 3425);
PAINT GREEN (-850 3425);
DISPLAY INVISIBLE (-850 3425);
FORCEPROP 1 LAST HDL_TAP TRUE
J 0
(-525 3250);
DISPLAY 0.872340 (-525 3250);
DISPLAY INVISIBLE (-525 3250);
FORCEPROP 1 LAST PATH I101
J 0
(-852 3375);
DISPLAY 0.872340 (-852 3375);
PAINT GREEN (-852 3375);
DISPLAY INVISIBLE (-852 3375);
FORCEADD TAP..1
(-850 3475);
FORCEPROP 3 LASTPIN (-900 3475) SIG_NAME M_H_CPU0_SA_DQ<21>
J 0
(-890 3485);
DISPLAY 0.659574 (-890 3485);
PAINT MONO (-890 3485);
DISPLAY INVISIBLE (-890 3485);
FORCEPROP 1 LASTPIN (-900 3475) BN 21
J 0
(-912 3483);
DISPLAY 0.680851 (-912 3483);
PAINT GREEN (-912 3483);
FORCEPROP 2 LAST CDS_LIB standard
J 0
(-850 3475);
PAINT MONO (-850 3475);
DISPLAY INVISIBLE (-850 3475);
FORCEPROP 1 LAST BODY_TYPE PLUMBING
J 0
(-850 3525);
DISPLAY 0.872340 (-850 3525);
PAINT GREEN (-850 3525);
DISPLAY INVISIBLE (-850 3525);
FORCEPROP 1 LAST HDL_TAP TRUE
J 0
(-525 3350);
DISPLAY 0.872340 (-525 3350);
DISPLAY INVISIBLE (-525 3350);
FORCEPROP 1 LAST PATH I102
J 0
(-852 3475);
DISPLAY 0.872340 (-852 3475);
PAINT GREEN (-852 3475);
DISPLAY INVISIBLE (-852 3475);
FORCEADD TAP..1
(-850 3525);
FORCEPROP 3 LASTPIN (-900 3525) SIG_NAME M_H_CPU0_SA_DQ<22>
J 0
(-890 3535);
DISPLAY 0.659574 (-890 3535);
PAINT MONO (-890 3535);
DISPLAY INVISIBLE (-890 3535);
FORCEPROP 1 LASTPIN (-900 3525) BN 22
J 0
(-912 3533);
DISPLAY 0.680851 (-912 3533);
PAINT GREEN (-912 3533);
FORCEPROP 2 LAST CDS_LIB standard
J 0
(-850 3525);
DISPLAY INVISIBLE (-850 3525);
FORCEPROP 1 LAST BODY_TYPE PLUMBING
J 0
(-850 3575);
DISPLAY 0.872340 (-850 3575);
PAINT GREEN (-850 3575);
DISPLAY INVISIBLE (-850 3575);
FORCEPROP 1 LAST HDL_TAP TRUE
J 0
(-525 3400);
DISPLAY 0.872340 (-525 3400);
DISPLAY INVISIBLE (-525 3400);
FORCEPROP 1 LAST PATH I103
J 0
(-852 3525);
DISPLAY 0.872340 (-852 3525);
PAINT GREEN (-852 3525);
DISPLAY INVISIBLE (-852 3525);
FORCEADD TAP..1
(-850 3575);
FORCEPROP 3 LASTPIN (-900 3575) SIG_NAME M_H_CPU0_SA_DQ<23>
J 0
(-890 3585);
DISPLAY 0.659574 (-890 3585);
PAINT MONO (-890 3585);
DISPLAY INVISIBLE (-890 3585);
FORCEPROP 1 LASTPIN (-900 3575) BN 23
J 0
(-912 3583);
DISPLAY 0.680851 (-912 3583);
PAINT GREEN (-912 3583);
FORCEPROP 2 LAST CDS_LIB standard
J 0
(-850 3575);
DISPLAY INVISIBLE (-850 3575);
FORCEPROP 1 LAST BODY_TYPE PLUMBING
J 0
(-850 3625);
DISPLAY 0.872340 (-850 3625);
PAINT GREEN (-850 3625);
DISPLAY INVISIBLE (-850 3625);
FORCEPROP 1 LAST HDL_TAP TRUE
J 0
(-525 3450);
DISPLAY 0.872340 (-525 3450);
DISPLAY INVISIBLE (-525 3450);
FORCEPROP 1 LAST PATH I104
J 0
(-852 3575);
DISPLAY 0.872340 (-852 3575);
PAINT GREEN (-852 3575);
DISPLAY INVISIBLE (-852 3575);
FORCEADD TAP..1
(-850 3675);
FORCEPROP 3 LASTPIN (-900 3675) SIG_NAME M_H_CPU0_SA_DQ<25>
J 0
(-890 3685);
DISPLAY 0.659574 (-890 3685);
PAINT MONO (-890 3685);
DISPLAY INVISIBLE (-890 3685);
FORCEPROP 1 LASTPIN (-900 3675) BN 25
J 0
(-912 3683);
DISPLAY 0.680851 (-912 3683);
PAINT GREEN (-912 3683);
FORCEPROP 2 LAST CDS_LIB standard
J 0
(-850 3675);
DISPLAY INVISIBLE (-850 3675);
FORCEPROP 1 LAST BODY_TYPE PLUMBING
J 0
(-850 3725);
DISPLAY 0.872340 (-850 3725);
PAINT GREEN (-850 3725);
DISPLAY INVISIBLE (-850 3725);
FORCEPROP 1 LAST HDL_TAP TRUE
J 0
(-525 3550);
DISPLAY 0.872340 (-525 3550);
DISPLAY INVISIBLE (-525 3550);
FORCEPROP 1 LAST PATH I105
J 0
(-852 3675);
DISPLAY 0.872340 (-852 3675);
PAINT GREEN (-852 3675);
DISPLAY INVISIBLE (-852 3675);
FORCEADD TAP..1
(-850 3625);
FORCEPROP 3 LASTPIN (-900 3625) SIG_NAME M_H_CPU0_SA_DQ<24>
J 0
(-890 3635);
DISPLAY 0.659574 (-890 3635);
PAINT MONO (-890 3635);
DISPLAY INVISIBLE (-890 3635);
FORCEPROP 1 LASTPIN (-900 3625) BN 24
J 0
(-912 3633);
DISPLAY 0.680851 (-912 3633);
PAINT GREEN (-912 3633);
FORCEPROP 2 LAST CDS_LIB standard
J 0
(-850 3625);
DISPLAY INVISIBLE (-850 3625);
FORCEPROP 1 LAST BODY_TYPE PLUMBING
J 0
(-850 3675);
DISPLAY 0.872340 (-850 3675);
PAINT GREEN (-850 3675);
DISPLAY INVISIBLE (-850 3675);
FORCEPROP 1 LAST HDL_TAP TRUE
J 0
(-525 3500);
DISPLAY 0.872340 (-525 3500);
DISPLAY INVISIBLE (-525 3500);
FORCEPROP 1 LAST PATH I106
J 0
(-852 3625);
DISPLAY 0.872340 (-852 3625);
PAINT GREEN (-852 3625);
DISPLAY INVISIBLE (-852 3625);
FORCEADD OFFPAGE..1
(-3425 4000);
FORCEPROP 2 LAST $XR1 97 
J 0
(-3736 4000);
DISPLAY 0.638298 (-3736 4000);
PAINT MONO (-3736 4000);
FORCEPROP 2 LAST $XR0 27 
J 0
(-3646 4000);
DISPLAY 0.638298 (-3646 4000);
PAINT MONO (-3646 4000);
FORCEPROP 2 LAST CDS_LIB standard
J 0
(-3425 4000);
PAINT MONO (-3425 4000);
DISPLAY INVISIBLE (-3425 4000);
FORCEPROP 1 LAST OFFPAGE TRUE
J 0
(-3100 3875);
DISPLAY 0.872340 (-3100 3875);
DISPLAY INVISIBLE (-3100 3875);
FORCEPROP 1 LAST COMMENT_BODY TRUE
J 0
(-3300 3900);
DISPLAY 0.872340 (-3300 3900);
PAINT GREEN (-3300 3900);
DISPLAY INVISIBLE (-3300 3900);
FORCEPROP 2 LAST PATH I107
J 0
(-3375 4075);
DISPLAY 1.021277 (-3375 4075);
DISPLAY INVISIBLE (-3375 4075);
FORCEADD TAP..1
R 2
(-2500 3775);
FORCEPROP 3 LASTPIN (-2450 3775) SIG_NAME M_H_CPU0_SA_CA<2>
J 0
(-2440 3785);
DISPLAY 0.659574 (-2440 3785);
PAINT MONO (-2440 3785);
DISPLAY INVISIBLE (-2440 3785);
FORCEPROP 1 LASTPIN (-2450 3775) BN 2
J 2
(-2438 3783);
DISPLAY 0.680851 (-2438 3783);
PAINT GREEN (-2438 3783);
FORCEPROP 2 LAST CDS_LIB standard
J 0
(-2500 3775);
DISPLAY INVISIBLE (-2500 3775);
FORCEPROP 1 LAST BODY_TYPE PLUMBING
J 2
(-2500 3825);
DISPLAY 0.872340 (-2500 3825);
PAINT GREEN (-2500 3825);
DISPLAY INVISIBLE (-2500 3825);
FORCEPROP 1 LAST HDL_TAP TRUE
J 2
(-2825 3650);
DISPLAY 0.872340 (-2825 3650);
DISPLAY INVISIBLE (-2825 3650);
FORCEPROP 1 LAST PATH I108
J 2
(-2498 3775);
DISPLAY 0.872340 (-2498 3775);
PAINT GREEN (-2498 3775);
DISPLAY INVISIBLE (-2498 3775);
FORCEADD TAP..1
R 2
(-2500 3725);
FORCEPROP 3 LASTPIN (-2450 3725) SIG_NAME M_H_CPU0_SA_CA<1>
J 0
(-2440 3735);
DISPLAY 0.659574 (-2440 3735);
PAINT MONO (-2440 3735);
DISPLAY INVISIBLE (-2440 3735);
FORCEPROP 1 LASTPIN (-2450 3725) BN 1
J 2
(-2438 3733);
DISPLAY 0.680851 (-2438 3733);
PAINT GREEN (-2438 3733);
FORCEPROP 2 LAST CDS_LIB standard
J 0
(-2500 3725);
DISPLAY INVISIBLE (-2500 3725);
FORCEPROP 1 LAST BODY_TYPE PLUMBING
J 2
(-2500 3775);
DISPLAY 0.872340 (-2500 3775);
PAINT GREEN (-2500 3775);
DISPLAY INVISIBLE (-2500 3775);
FORCEPROP 1 LAST HDL_TAP TRUE
J 2
(-2825 3600);
DISPLAY 0.872340 (-2825 3600);
DISPLAY INVISIBLE (-2825 3600);
FORCEPROP 1 LAST PATH I109
J 2
(-2498 3725);
DISPLAY 0.872340 (-2498 3725);
PAINT GREEN (-2498 3725);
DISPLAY INVISIBLE (-2498 3725);
FORCEADD OFFPAGE..3
R 2
(-3425 2150);
FORCEPROP 2 LAST $XR1 97 
J 0
(-3764 2150);
DISPLAY 0.638298 (-3764 2150);
PAINT MONO (-3764 2150);
FORCEPROP 2 LAST $XR0 27 
J 0
(-3674 2150);
DISPLAY 0.638298 (-3674 2150);
PAINT MONO (-3674 2150);
FORCEPROP 2 LAST CDS_LIB standard
J 0
(-3425 2150);
PAINT MONO (-3425 2150);
DISPLAY INVISIBLE (-3425 2150);
FORCEPROP 1 LAST OFFPAGE TRUE
J 2
(-3750 2025);
DISPLAY 0.872340 (-3750 2025);
DISPLAY INVISIBLE (-3750 2025);
FORCEPROP 1 LAST COMMENT_BODY TRUE
J 2
(-3375 2050);
DISPLAY 0.872340 (-3375 2050);
PAINT GREEN (-3375 2050);
DISPLAY INVISIBLE (-3375 2050);
FORCEPROP 2 LAST PATH I11
J 0
(-3375 2225);
DISPLAY 1.021277 (-3375 2225);
DISPLAY INVISIBLE (-3375 2225);
FORCEADD TAP..1
R 2
(-2500 3825);
FORCEPROP 3 LASTPIN (-2450 3825) SIG_NAME M_H_CPU0_SA_CA<3>
J 0
(-2440 3835);
DISPLAY 0.659574 (-2440 3835);
PAINT MONO (-2440 3835);
DISPLAY INVISIBLE (-2440 3835);
FORCEPROP 1 LASTPIN (-2450 3825) BN 3
J 2
(-2438 3833);
DISPLAY 0.680851 (-2438 3833);
PAINT GREEN (-2438 3833);
FORCEPROP 2 LAST CDS_LIB standard
J 0
(-2500 3825);
DISPLAY INVISIBLE (-2500 3825);
FORCEPROP 1 LAST BODY_TYPE PLUMBING
J 2
(-2500 3875);
DISPLAY 0.872340 (-2500 3875);
PAINT GREEN (-2500 3875);
DISPLAY INVISIBLE (-2500 3875);
FORCEPROP 1 LAST HDL_TAP TRUE
J 2
(-2825 3700);
DISPLAY 0.872340 (-2825 3700);
DISPLAY INVISIBLE (-2825 3700);
FORCEPROP 1 LAST PATH I110
J 2
(-2498 3825);
DISPLAY 0.872340 (-2498 3825);
PAINT GREEN (-2498 3825);
DISPLAY INVISIBLE (-2498 3825);
FORCEADD TAP..1
R 2
(-2500 3925);
FORCEPROP 3 LASTPIN (-2450 3925) SIG_NAME M_H_CPU0_SA_CA<5>
J 0
(-2440 3935);
DISPLAY 0.659574 (-2440 3935);
PAINT MONO (-2440 3935);
DISPLAY INVISIBLE (-2440 3935);
FORCEPROP 1 LASTPIN (-2450 3925) BN 5
J 2
(-2438 3933);
DISPLAY 0.680851 (-2438 3933);
PAINT GREEN (-2438 3933);
FORCEPROP 2 LAST CDS_LIB standard
J 0
(-2500 3925);
DISPLAY INVISIBLE (-2500 3925);
FORCEPROP 1 LAST BODY_TYPE PLUMBING
J 2
(-2500 3975);
DISPLAY 0.872340 (-2500 3975);
PAINT GREEN (-2500 3975);
DISPLAY INVISIBLE (-2500 3975);
FORCEPROP 1 LAST HDL_TAP TRUE
J 2
(-2825 3800);
DISPLAY 0.872340 (-2825 3800);
DISPLAY INVISIBLE (-2825 3800);
FORCEPROP 1 LAST PATH I111
J 2
(-2498 3925);
DISPLAY 0.872340 (-2498 3925);
PAINT GREEN (-2498 3925);
DISPLAY INVISIBLE (-2498 3925);
FORCEADD TAP..1
R 2
(-2500 3875);
FORCEPROP 3 LASTPIN (-2450 3875) SIG_NAME M_H_CPU0_SA_CA<4>
J 0
(-2440 3885);
DISPLAY 0.659574 (-2440 3885);
PAINT MONO (-2440 3885);
DISPLAY INVISIBLE (-2440 3885);
FORCEPROP 1 LASTPIN (-2450 3875) BN 4
J 2
(-2438 3883);
DISPLAY 0.680851 (-2438 3883);
PAINT GREEN (-2438 3883);
FORCEPROP 2 LAST CDS_LIB standard
J 0
(-2500 3875);
DISPLAY INVISIBLE (-2500 3875);
FORCEPROP 1 LAST BODY_TYPE PLUMBING
J 2
(-2500 3925);
DISPLAY 0.872340 (-2500 3925);
PAINT GREEN (-2500 3925);
DISPLAY INVISIBLE (-2500 3925);
FORCEPROP 1 LAST HDL_TAP TRUE
J 2
(-2825 3750);
DISPLAY 0.872340 (-2825 3750);
DISPLAY INVISIBLE (-2825 3750);
FORCEPROP 1 LAST PATH I112
J 2
(-2498 3875);
DISPLAY 0.872340 (-2498 3875);
PAINT GREEN (-2498 3875);
DISPLAY INVISIBLE (-2498 3875);
FORCEADD TAP..1
R 2
(-2500 3975);
FORCEPROP 3 LASTPIN (-2450 3975) SIG_NAME M_H_CPU0_SA_CA<6>
J 0
(-2440 3985);
DISPLAY 0.659574 (-2440 3985);
PAINT MONO (-2440 3985);
DISPLAY INVISIBLE (-2440 3985);
FORCEPROP 1 LASTPIN (-2450 3975) BN 6
J 2
(-2438 3983);
DISPLAY 0.680851 (-2438 3983);
PAINT GREEN (-2438 3983);
FORCEPROP 2 LAST CDS_LIB standard
J 0
(-2500 3975);
DISPLAY INVISIBLE (-2500 3975);
FORCEPROP 1 LAST BODY_TYPE PLUMBING
J 2
(-2500 4025);
DISPLAY 0.872340 (-2500 4025);
PAINT GREEN (-2500 4025);
DISPLAY INVISIBLE (-2500 4025);
FORCEPROP 1 LAST HDL_TAP TRUE
J 2
(-2825 3850);
DISPLAY 0.872340 (-2825 3850);
DISPLAY INVISIBLE (-2825 3850);
FORCEPROP 1 LAST PATH I113
J 2
(-2498 3975);
DISPLAY 0.872340 (-2498 3975);
PAINT GREEN (-2498 3975);
DISPLAY INVISIBLE (-2498 3975);
FORCEADD TAP..1
(-850 3775);
FORCEPROP 3 LASTPIN (-900 3775) SIG_NAME M_H_CPU0_SA_DQ<27>
J 0
(-890 3785);
DISPLAY 0.659574 (-890 3785);
PAINT MONO (-890 3785);
DISPLAY INVISIBLE (-890 3785);
FORCEPROP 1 LASTPIN (-900 3775) BN 27
J 0
(-912 3783);
DISPLAY 0.680851 (-912 3783);
PAINT GREEN (-912 3783);
FORCEPROP 2 LAST CDS_LIB standard
J 0
(-850 3775);
DISPLAY INVISIBLE (-850 3775);
FORCEPROP 1 LAST BODY_TYPE PLUMBING
J 0
(-850 3825);
DISPLAY 0.872340 (-850 3825);
PAINT GREEN (-850 3825);
DISPLAY INVISIBLE (-850 3825);
FORCEPROP 1 LAST HDL_TAP TRUE
J 0
(-525 3650);
DISPLAY 0.872340 (-525 3650);
DISPLAY INVISIBLE (-525 3650);
FORCEPROP 1 LAST PATH I114
J 0
(-852 3775);
DISPLAY 0.872340 (-852 3775);
PAINT GREEN (-852 3775);
DISPLAY INVISIBLE (-852 3775);
FORCEADD TAP..1
(-850 3725);
FORCEPROP 3 LASTPIN (-900 3725) SIG_NAME M_H_CPU0_SA_DQ<26>
J 0
(-890 3735);
DISPLAY 0.659574 (-890 3735);
PAINT MONO (-890 3735);
DISPLAY INVISIBLE (-890 3735);
FORCEPROP 1 LASTPIN (-900 3725) BN 26
J 0
(-912 3733);
DISPLAY 0.680851 (-912 3733);
PAINT GREEN (-912 3733);
FORCEPROP 2 LAST CDS_LIB standard
J 0
(-850 3725);
DISPLAY INVISIBLE (-850 3725);
FORCEPROP 1 LAST BODY_TYPE PLUMBING
J 0
(-850 3775);
DISPLAY 0.872340 (-850 3775);
PAINT GREEN (-850 3775);
DISPLAY INVISIBLE (-850 3775);
FORCEPROP 1 LAST HDL_TAP TRUE
J 0
(-525 3600);
DISPLAY 0.872340 (-525 3600);
DISPLAY INVISIBLE (-525 3600);
FORCEPROP 1 LAST PATH I115
J 0
(-852 3725);
DISPLAY 0.872340 (-852 3725);
PAINT GREEN (-852 3725);
DISPLAY INVISIBLE (-852 3725);
FORCEADD TAP..1
(-850 3825);
FORCEPROP 3 LASTPIN (-900 3825) SIG_NAME M_H_CPU0_SA_DQ<28>
J 0
(-890 3835);
DISPLAY 0.659574 (-890 3835);
PAINT MONO (-890 3835);
DISPLAY INVISIBLE (-890 3835);
FORCEPROP 1 LASTPIN (-900 3825) BN 28
J 0
(-912 3833);
DISPLAY 0.680851 (-912 3833);
PAINT GREEN (-912 3833);
FORCEPROP 2 LAST CDS_LIB standard
J 0
(-850 3825);
DISPLAY INVISIBLE (-850 3825);
FORCEPROP 1 LAST BODY_TYPE PLUMBING
J 0
(-850 3875);
DISPLAY 0.872340 (-850 3875);
PAINT GREEN (-850 3875);
DISPLAY INVISIBLE (-850 3875);
FORCEPROP 1 LAST HDL_TAP TRUE
J 0
(-525 3700);
DISPLAY 0.872340 (-525 3700);
DISPLAY INVISIBLE (-525 3700);
FORCEPROP 1 LAST PATH I116
J 0
(-852 3825);
DISPLAY 0.872340 (-852 3825);
PAINT GREEN (-852 3825);
DISPLAY INVISIBLE (-852 3825);
FORCEADD TAP..1
(-850 3875);
FORCEPROP 3 LASTPIN (-900 3875) SIG_NAME M_H_CPU0_SA_DQ<29>
J 0
(-890 3885);
DISPLAY 0.659574 (-890 3885);
PAINT MONO (-890 3885);
DISPLAY INVISIBLE (-890 3885);
FORCEPROP 1 LASTPIN (-900 3875) BN 29
J 0
(-912 3883);
DISPLAY 0.680851 (-912 3883);
PAINT GREEN (-912 3883);
FORCEPROP 2 LAST CDS_LIB standard
J 0
(-850 3875);
DISPLAY INVISIBLE (-850 3875);
FORCEPROP 1 LAST BODY_TYPE PLUMBING
J 0
(-850 3925);
DISPLAY 0.872340 (-850 3925);
PAINT GREEN (-850 3925);
DISPLAY INVISIBLE (-850 3925);
FORCEPROP 1 LAST HDL_TAP TRUE
J 0
(-525 3750);
DISPLAY 0.872340 (-525 3750);
DISPLAY INVISIBLE (-525 3750);
FORCEPROP 1 LAST PATH I117
J 0
(-852 3875);
DISPLAY 0.872340 (-852 3875);
PAINT GREEN (-852 3875);
DISPLAY INVISIBLE (-852 3875);
FORCEADD TAP..1
(-850 3975);
FORCEPROP 3 LASTPIN (-900 3975) SIG_NAME M_H_CPU0_SA_DQ<31>
J 0
(-890 3985);
DISPLAY 0.659574 (-890 3985);
PAINT MONO (-890 3985);
DISPLAY INVISIBLE (-890 3985);
FORCEPROP 1 LASTPIN (-900 3975) BN 31
J 0
(-912 3983);
DISPLAY 0.680851 (-912 3983);
PAINT GREEN (-912 3983);
FORCEPROP 2 LAST CDS_LIB standard
J 0
(-850 3975);
DISPLAY INVISIBLE (-850 3975);
FORCEPROP 1 LAST BODY_TYPE PLUMBING
J 0
(-850 4025);
DISPLAY 0.872340 (-850 4025);
PAINT GREEN (-850 4025);
DISPLAY INVISIBLE (-850 4025);
FORCEPROP 1 LAST HDL_TAP TRUE
J 0
(-525 3850);
DISPLAY 0.872340 (-525 3850);
DISPLAY INVISIBLE (-525 3850);
FORCEPROP 1 LAST PATH I118
J 0
(-852 3975);
DISPLAY 0.872340 (-852 3975);
PAINT GREEN (-852 3975);
DISPLAY INVISIBLE (-852 3975);
FORCEADD TAP..1
(-850 3925);
FORCEPROP 3 LASTPIN (-900 3925) SIG_NAME M_H_CPU0_SA_DQ<30>
J 0
(-890 3935);
DISPLAY 0.659574 (-890 3935);
PAINT MONO (-890 3935);
DISPLAY INVISIBLE (-890 3935);
FORCEPROP 1 LASTPIN (-900 3925) BN 30
J 0
(-912 3933);
DISPLAY 0.680851 (-912 3933);
PAINT GREEN (-912 3933);
FORCEPROP 2 LAST CDS_LIB standard
J 0
(-850 3925);
DISPLAY INVISIBLE (-850 3925);
FORCEPROP 1 LAST BODY_TYPE PLUMBING
J 0
(-850 3975);
DISPLAY 0.872340 (-850 3975);
PAINT GREEN (-850 3975);
DISPLAY INVISIBLE (-850 3975);
FORCEPROP 1 LAST HDL_TAP TRUE
J 0
(-525 3800);
DISPLAY 0.872340 (-525 3800);
DISPLAY INVISIBLE (-525 3800);
FORCEPROP 1 LAST PATH I119
J 0
(-852 3925);
DISPLAY 0.872340 (-852 3925);
PAINT GREEN (-852 3925);
DISPLAY INVISIBLE (-852 3925);
FORCEADD OFFPAGE..3
R 2
(-3425 2600);
FORCEPROP 2 LAST $XR1 97 
J 0
(-3764 2600);
DISPLAY 0.638298 (-3764 2600);
PAINT MONO (-3764 2600);
FORCEPROP 2 LAST $XR0 27 
J 0
(-3674 2600);
DISPLAY 0.638298 (-3674 2600);
PAINT MONO (-3674 2600);
FORCEPROP 2 LAST CDS_LIB standard
J 0
(-3425 2600);
PAINT MONO (-3425 2600);
DISPLAY INVISIBLE (-3425 2600);
FORCEPROP 1 LAST OFFPAGE TRUE
J 2
(-3750 2475);
DISPLAY 0.872340 (-3750 2475);
DISPLAY INVISIBLE (-3750 2475);
FORCEPROP 1 LAST COMMENT_BODY TRUE
J 2
(-3375 2500);
DISPLAY 0.872340 (-3375 2500);
PAINT GREEN (-3375 2500);
DISPLAY INVISIBLE (-3375 2500);
FORCEPROP 2 LAST PATH I12
J 0
(-3375 2675);
DISPLAY 1.021277 (-3375 2675);
DISPLAY INVISIBLE (-3375 2675);
FORCEADD UNIVERSAL_GND..1
(875 -275);
FORCEPROP 3 LASTPIN (875 -225) SIG_NAME GND\g
J 0
(885 -215);
DISPLAY 0.659574 (885 -215);
PAINT MONO (885 -215);
DISPLAY INVISIBLE (885 -215);
FORCEPROP 2 LAST CDS_LIB logical_power
J 0
(875 -275);
PAINT MONO (875 -275);
DISPLAY INVISIBLE (875 -275);
FORCEPROP 1 LAST HDL_POWER GND
J 1
(900 -350);
DISPLAY 0.872340 (900 -350);
PAINT GREEN (900 -350);
DISPLAY INVISIBLE (900 -350);
FORCEPROP 1 LAST PATH I120
J 0
(950 -275);
DISPLAY 0.872340 (950 -275);
PAINT AQUA (950 -275);
DISPLAY INVISIBLE (950 -275);
FORCEADD Q_CAP..1
(875 100);
FORCEPROP 1 LAST PART_NUMBER CH5221MEB00
J 0
(925 -50);
DISPLAY 0.978723 (925 -50);
DISPLAY INVISIBLE (925 -50);
FORCEPROP 1 LAST PACK_TYPE C0402
J 0
(925 -100);
DISPLAY 0.978723 (925 -100);
FORCEPROP 1 LAST MATERIAL X6S
J 0
(925 0);
DISPLAY 0.978723 (925 0);
FORCEPROP 1 LAST TOLERANCE 20%
J 0
(925 50);
DISPLAY 0.978723 (925 50);
FORCEPROP 1 LAST VOLTAGE 6.3V
J 0
(925 100);
DISPLAY 0.978723 (925 100);
FORCEPROP 1 LAST VALUE 2.2UF
J 0
(925 150);
DISPLAY 0.978723 (925 150);
FORCEPROP 1 LAST $LOCATION C44
J 0
(925 200);
DISPLAY 0.978723 (925 200);
FORCEPROP 1 LASTPIN (875 200) $PN 1
J 0
(885 180);
DISPLAY 0.787234 (885 180);
FORCEPROP 1 LASTPIN (875 0) $PN 2
J 0
(885 -20);
DISPLAY 0.787234 (885 -20);
FORCEPROP 2 LAST CDS_LIB pure_quanta
J 0
(875 100);
PAINT MONO (875 100);
DISPLAY INVISIBLE (875 100);
FORCEPROP 2 LAST CDS_LOCATION C44
J 0
(925 300);
DISPLAY 1.021277 (925 300);
DISPLAY INVISIBLE (925 300);
FORCEPROP 2 LAST $SEC 1
J 0
(925 300);
DISPLAY 0.680851 (925 300);
PAINT MONO (925 300);
DISPLAY INVISIBLE (925 300);
FORCEPROP 2 LAST CDS_SEC 1
J 0
(925 300);
DISPLAY 1.021277 (925 300);
DISPLAY INVISIBLE (925 300);
FORCEPROP 1 LAST PATH I121
J 0
(925 250);
DISPLAY 0.978723 (925 250);
PAINT WHITE (925 250);
DISPLAY INVISIBLE (925 250);
FORCEADD VCC_CORE..1
(875 425);
FORCEPROP 3 LASTPIN (875 375) SIG_NAME P3V3_AUX\g
J 0
(885 385);
DISPLAY 0.659574 (885 385);
PAINT MONO (885 385);
DISPLAY INVISIBLE (885 385);
FORCEPROP 1 LAST HDL_POWER P3V3_AUX
J 1
(875 475);
DISPLAY 1.148936 (875 475);
PAINT GREEN (875 475);
FORCEPROP 2 LAST CDS_LIB logical_power
J 0
(875 425);
PAINT MONO (875 425);
DISPLAY INVISIBLE (875 425);
FORCEPROP 1 LAST PATH I122
J 0
(925 450);
DISPLAY 0.872340 (925 450);
PAINT AQUA (925 450);
DISPLAY INVISIBLE (925 450);
FORCEADD OFFPAGE..3
(-25 2350);
FORCEPROP 2 LAST $XR1 97 
J 0
(279 2350);
DISPLAY 0.638298 (279 2350);
PAINT MONO (279 2350);
FORCEPROP 2 LAST $XR0 27 
J 0
(189 2350);
DISPLAY 0.638298 (189 2350);
PAINT MONO (189 2350);
FORCEPROP 2 LAST CDS_LIB standard
J 2
(-25 2350);
DISPLAY INVISIBLE (-25 2350);
FORCEPROP 1 LAST OFFPAGE TRUE
J 0
(300 2225);
DISPLAY 0.872340 (300 2225);
DISPLAY INVISIBLE (300 2225);
FORCEPROP 1 LAST COMMENT_BODY TRUE
J 0
(-75 2250);
DISPLAY 0.872340 (-75 2250);
PAINT GREEN (-75 2250);
DISPLAY INVISIBLE (-75 2250);
FORCEPROP 2 LAST PATH I123
J 0
(175 2425);
DISPLAY 1.021277 (175 2425);
DISPLAY INVISIBLE (175 2425);
FORCEADD Q_CAP..1
(1875 100);
FORCEPROP 1 LAST PART_NUMBER CH6103KEA00
J 0
(1925 -50);
DISPLAY 0.978723 (1925 -50);
DISPLAY INVISIBLE (1925 -50);
FORCEPROP 1 LAST PACK_TYPE C0805
J 0
(1925 -100);
DISPLAY 0.978723 (1925 -100);
FORCEPROP 1 LAST TOLERANCE 10%
J 0
(1925 50);
DISPLAY 0.978723 (1925 50);
FORCEPROP 1 LAST VOLTAGE 16V
J 0
(1925 100);
DISPLAY 0.978723 (1925 100);
FORCEPROP 1 LAST VALUE 10UF
J 0
(1925 150);
DISPLAY 0.978723 (1925 150);
FORCEPROP 1 LAST MATERIAL X6S
J 0
(1925 0);
DISPLAY 0.978723 (1925 0);
FORCEPROP 1 LAST $LOCATION C45
J 0
(1925 200);
DISPLAY 0.978723 (1925 200);
FORCEPROP 1 LASTPIN (1875 200) $PN 1
J 0
(1885 180);
DISPLAY 0.787234 (1885 180);
FORCEPROP 1 LASTPIN (1875 0) $PN 2
J 0
(1885 -20);
DISPLAY 0.787234 (1885 -20);
FORCEPROP 2 LAST CDS_LIB pure_quanta
J 0
(1875 100);
PAINT MONO (1875 100);
DISPLAY INVISIBLE (1875 100);
FORCEPROP 2 LAST CDS_LOCATION C45
J 0
(1925 300);
DISPLAY 1.021277 (1925 300);
DISPLAY INVISIBLE (1925 300);
FORCEPROP 2 LAST $SEC 1
J 0
(1925 300);
DISPLAY 0.680851 (1925 300);
PAINT MONO (1925 300);
DISPLAY INVISIBLE (1925 300);
FORCEPROP 2 LAST CDS_SEC 1
J 0
(1925 300);
DISPLAY 1.021277 (1925 300);
DISPLAY INVISIBLE (1925 300);
FORCEPROP 1 LAST PATH I125
J 0
(1925 250);
DISPLAY 0.978723 (1925 250);
PAINT WHITE (1925 250);
DISPLAY INVISIBLE (1925 250);
FORCEADD VCC_CORE..1
(1875 425);
FORCEPROP 3 LASTPIN (1875 375) SIG_NAME P12V_S3_AUX_CPU0_NVDIMM\g
J 0
(1885 385);
DISPLAY 0.659574 (1885 385);
PAINT MONO (1885 385);
DISPLAY INVISIBLE (1885 385);
FORCEPROP 1 LAST HDL_POWER P12V_S3_AUX_CPU0_NVDIMM
J 1
(1875 475);
DISPLAY 1.148936 (1875 475);
PAINT GREEN (1875 475);
FORCEPROP 2 LAST CDS_LIB logical_power
J 0
(1875 425);
PAINT MONO (1875 425);
DISPLAY INVISIBLE (1875 425);
FORCEPROP 1 LAST PATH I126
J 0
(1925 450);
DISPLAY 0.872340 (1925 450);
PAINT AQUA (1925 450);
DISPLAY INVISIBLE (1925 450);
FORCEADD Q_CAP..1
(2500 100);
FORCEPROP 1 LAST PART_NUMBER CH6103KEA00
J 0
(2550 -50);
DISPLAY 0.978723 (2550 -50);
DISPLAY INVISIBLE (2550 -50);
FORCEPROP 1 LAST PACK_TYPE C0805
J 0
(2550 -100);
DISPLAY 0.978723 (2550 -100);
FORCEPROP 1 LAST VALUE 10UF
J 0
(2550 150);
DISPLAY 0.978723 (2550 150);
FORCEPROP 1 LAST VOLTAGE 16V
J 0
(2550 100);
DISPLAY 0.978723 (2550 100);
FORCEPROP 1 LAST TOLERANCE 10%
J 0
(2550 50);
DISPLAY 0.978723 (2550 50);
FORCEPROP 1 LAST MATERIAL X6S
J 0
(2550 0);
DISPLAY 0.978723 (2550 0);
FORCEPROP 1 LAST $LOCATION C46
J 0
(2550 200);
DISPLAY 0.978723 (2550 200);
FORCEPROP 1 LASTPIN (2500 200) $PN 1
J 0
(2510 180);
DISPLAY 0.787234 (2510 180);
FORCEPROP 1 LASTPIN (2500 0) $PN 2
J 0
(2510 -20);
DISPLAY 0.787234 (2510 -20);
FORCEPROP 2 LAST CDS_LIB pure_quanta
J 0
(2500 100);
PAINT MONO (2500 100);
DISPLAY INVISIBLE (2500 100);
FORCEPROP 2 LAST CDS_LOCATION C46
J 0
(2550 300);
DISPLAY 1.021277 (2550 300);
DISPLAY INVISIBLE (2550 300);
FORCEPROP 2 LAST $SEC 1
J 0
(2550 300);
DISPLAY 0.680851 (2550 300);
PAINT MONO (2550 300);
DISPLAY INVISIBLE (2550 300);
FORCEPROP 2 LAST CDS_SEC 1
J 0
(2550 300);
DISPLAY 1.021277 (2550 300);
DISPLAY INVISIBLE (2550 300);
FORCEPROP 1 LAST PATH I127
J 0
(2550 250);
DISPLAY 0.978723 (2550 250);
PAINT WHITE (2550 250);
DISPLAY INVISIBLE (2550 250);
FORCEADD UNIVERSAL_GND..1
(2500 -275);
FORCEPROP 3 LASTPIN (2500 -225) SIG_NAME GND\g
J 0
(2510 -215);
DISPLAY 0.659574 (2510 -215);
PAINT MONO (2510 -215);
DISPLAY INVISIBLE (2510 -215);
FORCEPROP 2 LAST CDS_LIB logical_power
J 0
(2500 -275);
PAINT MONO (2500 -275);
DISPLAY INVISIBLE (2500 -275);
FORCEPROP 1 LAST HDL_POWER GND
J 1
(2525 -350);
DISPLAY 0.872340 (2525 -350);
PAINT GREEN (2525 -350);
DISPLAY INVISIBLE (2525 -350);
FORCEPROP 1 LAST PATH I128
J 0
(2575 -275);
DISPLAY 0.872340 (2575 -275);
PAINT AQUA (2575 -275);
DISPLAY INVISIBLE (2575 -275);
FORCEADD UNIVERSAL_GND..1
(3575 275);
FORCEPROP 3 LASTPIN (3575 325) SIG_NAME GND\g
J 0
(3585 335);
DISPLAY 0.659574 (3585 335);
PAINT MONO (3585 335);
DISPLAY INVISIBLE (3585 335);
FORCEPROP 2 LAST CDS_LIB logical_power
J 0
(3575 275);
PAINT MONO (3575 275);
DISPLAY INVISIBLE (3575 275);
FORCEPROP 1 LAST HDL_POWER GND
J 1
(3600 200);
DISPLAY 0.872340 (3600 200);
PAINT GREEN (3600 200);
DISPLAY INVISIBLE (3600 200);
FORCEPROP 1 LAST PATH I129
J 0
(3650 275);
DISPLAY 0.872340 (3650 275);
PAINT AQUA (3650 275);
DISPLAY INVISIBLE (3650 275);
FORCEADD OFFPAGE..1
(-3425 2675);
FORCEPROP 2 LAST $XR0 27 
J 0
(-3646 2675);
DISPLAY 0.638298 (-3646 2675);
PAINT MONO (-3646 2675);
FORCEPROP 2 LAST CDS_LIB standard
J 0
(-3425 2675);
PAINT MONO (-3425 2675);
DISPLAY INVISIBLE (-3425 2675);
FORCEPROP 1 LAST OFFPAGE TRUE
J 0
(-3100 2550);
DISPLAY 0.872340 (-3100 2550);
DISPLAY INVISIBLE (-3100 2550);
FORCEPROP 1 LAST COMMENT_BODY TRUE
J 0
(-3300 2575);
DISPLAY 0.872340 (-3300 2575);
PAINT GREEN (-3300 2575);
DISPLAY INVISIBLE (-3300 2575);
FORCEPROP 2 LAST PATH I13
J 0
(-3375 2750);
DISPLAY 1.021277 (-3375 2750);
DISPLAY INVISIBLE (-3375 2750);
FORCEADD TAP..1
(1900 2125);
FORCEPROP 3 LASTPIN (1850 2125) SIG_NAME M_H_CPU0_SB_DQS_DP<1>
J 0
(1860 2135);
DISPLAY 0.659574 (1860 2135);
PAINT MONO (1860 2135);
DISPLAY INVISIBLE (1860 2135);
FORCEPROP 1 LASTPIN (1850 2125) BN 1
J 0
(1838 2133);
DISPLAY 0.680851 (1838 2133);
PAINT GREEN (1838 2133);
FORCEPROP 2 LAST CDS_LIB standard
J 0
(1900 2125);
DISPLAY INVISIBLE (1900 2125);
FORCEPROP 1 LAST BODY_TYPE PLUMBING
J 0
(1900 2175);
DISPLAY 0.872340 (1900 2175);
PAINT GREEN (1900 2175);
DISPLAY INVISIBLE (1900 2175);
FORCEPROP 1 LAST HDL_TAP TRUE
J 0
(2225 2000);
DISPLAY 0.872340 (2225 2000);
DISPLAY INVISIBLE (2225 2000);
FORCEPROP 1 LAST PATH I130
J 0
(1898 2125);
DISPLAY 0.872340 (1898 2125);
PAINT GREEN (1898 2125);
DISPLAY INVISIBLE (1898 2125);
FORCEADD TAP..1
(1900 2025);
FORCEPROP 3 LASTPIN (1850 2025) SIG_NAME M_H_CPU0_SB_DQS_DP<0>
J 0
(1860 2035);
DISPLAY 0.659574 (1860 2035);
PAINT MONO (1860 2035);
DISPLAY INVISIBLE (1860 2035);
FORCEPROP 1 LASTPIN (1850 2025) BN 0
J 0
(1838 2033);
DISPLAY 0.680851 (1838 2033);
PAINT GREEN (1838 2033);
FORCEPROP 2 LAST CDS_LIB standard
J 0
(1900 2025);
PAINT MONO (1900 2025);
DISPLAY INVISIBLE (1900 2025);
FORCEPROP 1 LAST BODY_TYPE PLUMBING
J 0
(1900 2075);
DISPLAY 0.872340 (1900 2075);
PAINT GREEN (1900 2075);
DISPLAY INVISIBLE (1900 2075);
FORCEPROP 1 LAST HDL_TAP TRUE
J 0
(2225 1900);
DISPLAY 0.872340 (2225 1900);
DISPLAY INVISIBLE (2225 1900);
FORCEPROP 1 LAST PATH I131
J 0
(1898 2025);
DISPLAY 0.872340 (1898 2025);
PAINT GREEN (1898 2025);
DISPLAY INVISIBLE (1898 2025);
FORCEADD TAP..1
(2075 1975);
FORCEPROP 3 LASTPIN (2025 1975) SIG_NAME M_H_CPU0_SB_DQS_DN<0>
J 0
(2035 1985);
DISPLAY 0.659574 (2035 1985);
PAINT MONO (2035 1985);
DISPLAY INVISIBLE (2035 1985);
FORCEPROP 1 LASTPIN (2025 1975) BN 0
J 0
(2013 1983);
DISPLAY 0.680851 (2013 1983);
PAINT GREEN (2013 1983);
FORCEPROP 2 LAST CDS_LIB standard
J 0
(2075 1975);
PAINT MONO (2075 1975);
DISPLAY INVISIBLE (2075 1975);
FORCEPROP 1 LAST BODY_TYPE PLUMBING
J 0
(2075 2025);
DISPLAY 0.872340 (2075 2025);
PAINT GREEN (2075 2025);
DISPLAY INVISIBLE (2075 2025);
FORCEPROP 1 LAST HDL_TAP TRUE
J 0
(2400 1850);
DISPLAY 0.872340 (2400 1850);
DISPLAY INVISIBLE (2400 1850);
FORCEPROP 1 LAST PATH I132
J 0
(2073 1975);
DISPLAY 0.872340 (2073 1975);
PAINT GREEN (2073 1975);
DISPLAY INVISIBLE (2073 1975);
FORCEADD TAP..1
(2075 2075);
FORCEPROP 3 LASTPIN (2025 2075) SIG_NAME M_H_CPU0_SB_DQS_DN<1>
J 0
(2035 2085);
DISPLAY 0.659574 (2035 2085);
PAINT MONO (2035 2085);
DISPLAY INVISIBLE (2035 2085);
FORCEPROP 1 LASTPIN (2025 2075) BN 1
J 0
(2013 2083);
DISPLAY 0.680851 (2013 2083);
PAINT GREEN (2013 2083);
FORCEPROP 2 LAST CDS_LIB standard
J 0
(2075 2075);
DISPLAY INVISIBLE (2075 2075);
FORCEPROP 1 LAST BODY_TYPE PLUMBING
J 0
(2075 2125);
DISPLAY 0.872340 (2075 2125);
PAINT GREEN (2075 2125);
DISPLAY INVISIBLE (2075 2125);
FORCEPROP 1 LAST HDL_TAP TRUE
J 0
(2400 1950);
DISPLAY 0.872340 (2400 1950);
DISPLAY INVISIBLE (2400 1950);
FORCEPROP 1 LAST PATH I133
J 0
(2073 2075);
DISPLAY 0.872340 (2073 2075);
PAINT GREEN (2073 2075);
DISPLAY INVISIBLE (2073 2075);
FORCEADD TAP..1
(2075 2175);
FORCEPROP 3 LASTPIN (2025 2175) SIG_NAME M_H_CPU0_SB_DQS_DN<2>
J 0
(2035 2185);
DISPLAY 0.659574 (2035 2185);
PAINT MONO (2035 2185);
DISPLAY INVISIBLE (2035 2185);
FORCEPROP 1 LASTPIN (2025 2175) BN 2
J 0
(2013 2183);
DISPLAY 0.680851 (2013 2183);
PAINT GREEN (2013 2183);
FORCEPROP 2 LAST CDS_LIB standard
J 0
(2075 2175);
DISPLAY INVISIBLE (2075 2175);
FORCEPROP 1 LAST BODY_TYPE PLUMBING
J 0
(2075 2225);
DISPLAY 0.872340 (2075 2225);
PAINT GREEN (2075 2225);
DISPLAY INVISIBLE (2075 2225);
FORCEPROP 1 LAST HDL_TAP TRUE
J 0
(2400 2050);
DISPLAY 0.872340 (2400 2050);
DISPLAY INVISIBLE (2400 2050);
FORCEPROP 1 LAST PATH I134
J 0
(2073 2175);
DISPLAY 0.872340 (2073 2175);
PAINT GREEN (2073 2175);
DISPLAY INVISIBLE (2073 2175);
FORCEADD TAP..1
(1900 2225);
FORCEPROP 3 LASTPIN (1850 2225) SIG_NAME M_H_CPU0_SB_DQS_DP<2>
J 0
(1860 2235);
DISPLAY 0.659574 (1860 2235);
PAINT MONO (1860 2235);
DISPLAY INVISIBLE (1860 2235);
FORCEPROP 1 LASTPIN (1850 2225) BN 2
J 0
(1838 2233);
DISPLAY 0.680851 (1838 2233);
PAINT GREEN (1838 2233);
FORCEPROP 2 LAST CDS_LIB standard
J 0
(1900 2225);
DISPLAY INVISIBLE (1900 2225);
FORCEPROP 1 LAST BODY_TYPE PLUMBING
J 0
(1900 2275);
DISPLAY 0.872340 (1900 2275);
PAINT GREEN (1900 2275);
DISPLAY INVISIBLE (1900 2275);
FORCEPROP 1 LAST HDL_TAP TRUE
J 0
(2225 2100);
DISPLAY 0.872340 (2225 2100);
DISPLAY INVISIBLE (2225 2100);
FORCEPROP 1 LAST PATH I135
J 0
(1898 2225);
DISPLAY 0.872340 (1898 2225);
PAINT GREEN (1898 2225);
DISPLAY INVISIBLE (1898 2225);
FORCEADD TAP..1
(1900 2325);
FORCEPROP 3 LASTPIN (1850 2325) SIG_NAME M_H_CPU0_SB_DQS_DP<3>
J 0
(1860 2335);
DISPLAY 0.659574 (1860 2335);
PAINT MONO (1860 2335);
DISPLAY INVISIBLE (1860 2335);
FORCEPROP 1 LASTPIN (1850 2325) BN 3
J 0
(1838 2333);
DISPLAY 0.680851 (1838 2333);
PAINT GREEN (1838 2333);
FORCEPROP 2 LAST CDS_LIB standard
J 0
(1900 2325);
PAINT MONO (1900 2325);
DISPLAY INVISIBLE (1900 2325);
FORCEPROP 1 LAST BODY_TYPE PLUMBING
J 0
(1900 2375);
DISPLAY 0.872340 (1900 2375);
PAINT GREEN (1900 2375);
DISPLAY INVISIBLE (1900 2375);
FORCEPROP 1 LAST HDL_TAP TRUE
J 0
(2225 2200);
DISPLAY 0.872340 (2225 2200);
DISPLAY INVISIBLE (2225 2200);
FORCEPROP 1 LAST PATH I136
J 0
(1898 2325);
DISPLAY 0.872340 (1898 2325);
PAINT GREEN (1898 2325);
DISPLAY INVISIBLE (1898 2325);
FORCEADD TAP..1
(1900 2425);
FORCEPROP 3 LASTPIN (1850 2425) SIG_NAME M_H_CPU0_SB_DQS_DP<4>
J 0
(1860 2435);
DISPLAY 0.659574 (1860 2435);
PAINT MONO (1860 2435);
DISPLAY INVISIBLE (1860 2435);
FORCEPROP 1 LASTPIN (1850 2425) BN 4
J 0
(1838 2433);
DISPLAY 0.680851 (1838 2433);
PAINT GREEN (1838 2433);
FORCEPROP 2 LAST CDS_LIB standard
J 0
(1900 2425);
PAINT MONO (1900 2425);
DISPLAY INVISIBLE (1900 2425);
FORCEPROP 1 LAST BODY_TYPE PLUMBING
J 0
(1900 2475);
DISPLAY 0.872340 (1900 2475);
PAINT GREEN (1900 2475);
DISPLAY INVISIBLE (1900 2475);
FORCEPROP 1 LAST HDL_TAP TRUE
J 0
(2225 2300);
DISPLAY 0.872340 (2225 2300);
DISPLAY INVISIBLE (2225 2300);
FORCEPROP 1 LAST PATH I137
J 0
(1898 2425);
DISPLAY 0.872340 (1898 2425);
PAINT GREEN (1898 2425);
DISPLAY INVISIBLE (1898 2425);
FORCEADD TAP..1
(2075 2275);
FORCEPROP 3 LASTPIN (2025 2275) SIG_NAME M_H_CPU0_SB_DQS_DN<3>
J 0
(2035 2285);
DISPLAY 0.659574 (2035 2285);
PAINT MONO (2035 2285);
DISPLAY INVISIBLE (2035 2285);
FORCEPROP 1 LASTPIN (2025 2275) BN 3
J 0
(2013 2283);
DISPLAY 0.680851 (2013 2283);
PAINT GREEN (2013 2283);
FORCEPROP 2 LAST CDS_LIB standard
J 0
(2075 2275);
PAINT MONO (2075 2275);
DISPLAY INVISIBLE (2075 2275);
FORCEPROP 1 LAST BODY_TYPE PLUMBING
J 0
(2075 2325);
DISPLAY 0.872340 (2075 2325);
PAINT GREEN (2075 2325);
DISPLAY INVISIBLE (2075 2325);
FORCEPROP 1 LAST HDL_TAP TRUE
J 0
(2400 2150);
DISPLAY 0.872340 (2400 2150);
DISPLAY INVISIBLE (2400 2150);
FORCEPROP 1 LAST PATH I138
J 0
(2073 2275);
DISPLAY 0.872340 (2073 2275);
PAINT GREEN (2073 2275);
DISPLAY INVISIBLE (2073 2275);
FORCEADD TAP..1
(2075 2375);
FORCEPROP 3 LASTPIN (2025 2375) SIG_NAME M_H_CPU0_SB_DQS_DN<4>
J 0
(2035 2385);
DISPLAY 0.659574 (2035 2385);
PAINT MONO (2035 2385);
DISPLAY INVISIBLE (2035 2385);
FORCEPROP 1 LASTPIN (2025 2375) BN 4
J 0
(2013 2383);
DISPLAY 0.680851 (2013 2383);
PAINT GREEN (2013 2383);
FORCEPROP 2 LAST CDS_LIB standard
J 0
(2075 2375);
PAINT MONO (2075 2375);
DISPLAY INVISIBLE (2075 2375);
FORCEPROP 1 LAST BODY_TYPE PLUMBING
J 0
(2075 2425);
DISPLAY 0.872340 (2075 2425);
PAINT GREEN (2075 2425);
DISPLAY INVISIBLE (2075 2425);
FORCEPROP 1 LAST HDL_TAP TRUE
J 0
(2400 2250);
DISPLAY 0.872340 (2400 2250);
DISPLAY INVISIBLE (2400 2250);
FORCEPROP 1 LAST PATH I139
J 0
(2073 2375);
DISPLAY 0.872340 (2073 2375);
PAINT GREEN (2073 2375);
DISPLAY INVISIBLE (2073 2375);
FORCEADD OFFPAGE..1
(-3425 2725);
FORCEPROP 2 LAST $XR0 27 
J 0
(-3646 2725);
DISPLAY 0.638298 (-3646 2725);
PAINT MONO (-3646 2725);
FORCEPROP 2 LAST CDS_LIB standard
J 0
(-3425 2725);
PAINT MONO (-3425 2725);
DISPLAY INVISIBLE (-3425 2725);
FORCEPROP 1 LAST OFFPAGE TRUE
J 0
(-3100 2600);
DISPLAY 0.872340 (-3100 2600);
DISPLAY INVISIBLE (-3100 2600);
FORCEPROP 1 LAST COMMENT_BODY TRUE
J 0
(-3300 2625);
DISPLAY 0.872340 (-3300 2625);
PAINT GREEN (-3300 2625);
DISPLAY INVISIBLE (-3300 2625);
FORCEPROP 2 LAST PATH I14
J 0
(-3375 2800);
DISPLAY 1.021277 (-3375 2800);
DISPLAY INVISIBLE (-3375 2800);
FORCEADD TAP..1
(1900 2625);
FORCEPROP 3 LASTPIN (1850 2625) SIG_NAME M_H_CPU0_SB_DQS_DP<6>
J 0
(1860 2635);
DISPLAY 0.659574 (1860 2635);
PAINT MONO (1860 2635);
DISPLAY INVISIBLE (1860 2635);
FORCEPROP 1 LASTPIN (1850 2625) BN 6
J 0
(1838 2633);
DISPLAY 0.680851 (1838 2633);
PAINT GREEN (1838 2633);
FORCEPROP 2 LAST CDS_LIB standard
J 0
(1900 2625);
DISPLAY INVISIBLE (1900 2625);
FORCEPROP 1 LAST BODY_TYPE PLUMBING
J 0
(1900 2675);
DISPLAY 0.872340 (1900 2675);
PAINT GREEN (1900 2675);
DISPLAY INVISIBLE (1900 2675);
FORCEPROP 1 LAST HDL_TAP TRUE
J 0
(2225 2500);
DISPLAY 0.872340 (2225 2500);
DISPLAY INVISIBLE (2225 2500);
FORCEPROP 1 LAST PATH I140
J 0
(1898 2625);
DISPLAY 0.872340 (1898 2625);
PAINT GREEN (1898 2625);
DISPLAY INVISIBLE (1898 2625);
FORCEADD TAP..1
(1900 2525);
FORCEPROP 3 LASTPIN (1850 2525) SIG_NAME M_H_CPU0_SB_DQS_DP<5>
J 0
(1860 2535);
DISPLAY 0.659574 (1860 2535);
PAINT MONO (1860 2535);
DISPLAY INVISIBLE (1860 2535);
FORCEPROP 1 LASTPIN (1850 2525) BN 5
J 0
(1838 2533);
DISPLAY 0.680851 (1838 2533);
PAINT GREEN (1838 2533);
FORCEPROP 2 LAST CDS_LIB standard
J 0
(1900 2525);
DISPLAY INVISIBLE (1900 2525);
FORCEPROP 1 LAST BODY_TYPE PLUMBING
J 0
(1900 2575);
DISPLAY 0.872340 (1900 2575);
PAINT GREEN (1900 2575);
DISPLAY INVISIBLE (1900 2575);
FORCEPROP 1 LAST HDL_TAP TRUE
J 0
(2225 2400);
DISPLAY 0.872340 (2225 2400);
DISPLAY INVISIBLE (2225 2400);
FORCEPROP 1 LAST PATH I141
J 0
(1898 2525);
DISPLAY 0.872340 (1898 2525);
PAINT GREEN (1898 2525);
DISPLAY INVISIBLE (1898 2525);
FORCEADD TAP..1
(2075 2575);
FORCEPROP 3 LASTPIN (2025 2575) SIG_NAME M_H_CPU0_SB_DQS_DN<6>
J 0
(2035 2585);
DISPLAY 0.659574 (2035 2585);
PAINT MONO (2035 2585);
DISPLAY INVISIBLE (2035 2585);
FORCEPROP 1 LASTPIN (2025 2575) BN 6
J 0
(2013 2583);
DISPLAY 0.680851 (2013 2583);
PAINT GREEN (2013 2583);
FORCEPROP 2 LAST CDS_LIB standard
J 0
(2075 2575);
DISPLAY INVISIBLE (2075 2575);
FORCEPROP 1 LAST BODY_TYPE PLUMBING
J 0
(2075 2625);
DISPLAY 0.872340 (2075 2625);
PAINT GREEN (2075 2625);
DISPLAY INVISIBLE (2075 2625);
FORCEPROP 1 LAST HDL_TAP TRUE
J 0
(2400 2450);
DISPLAY 0.872340 (2400 2450);
DISPLAY INVISIBLE (2400 2450);
FORCEPROP 1 LAST PATH I142
J 0
(2073 2575);
DISPLAY 0.872340 (2073 2575);
PAINT GREEN (2073 2575);
DISPLAY INVISIBLE (2073 2575);
FORCEADD TAP..1
(2075 2675);
FORCEPROP 3 LASTPIN (2025 2675) SIG_NAME M_H_CPU0_SB_DQS_DN<7>
J 0
(2035 2685);
DISPLAY 0.659574 (2035 2685);
PAINT MONO (2035 2685);
DISPLAY INVISIBLE (2035 2685);
FORCEPROP 1 LASTPIN (2025 2675) BN 7
J 0
(2013 2683);
DISPLAY 0.680851 (2013 2683);
PAINT GREEN (2013 2683);
FORCEPROP 2 LAST CDS_LIB standard
J 0
(2075 2675);
DISPLAY INVISIBLE (2075 2675);
FORCEPROP 1 LAST BODY_TYPE PLUMBING
J 0
(2075 2725);
DISPLAY 0.872340 (2075 2725);
PAINT GREEN (2075 2725);
DISPLAY INVISIBLE (2075 2725);
FORCEPROP 1 LAST HDL_TAP TRUE
J 0
(2400 2550);
DISPLAY 0.872340 (2400 2550);
DISPLAY INVISIBLE (2400 2550);
FORCEPROP 1 LAST PATH I143
J 0
(2073 2675);
DISPLAY 0.872340 (2073 2675);
PAINT GREEN (2073 2675);
DISPLAY INVISIBLE (2073 2675);
FORCEADD TAP..1
(2075 2475);
FORCEPROP 3 LASTPIN (2025 2475) SIG_NAME M_H_CPU0_SB_DQS_DN<5>
J 0
(2035 2485);
DISPLAY 0.659574 (2035 2485);
PAINT MONO (2035 2485);
DISPLAY INVISIBLE (2035 2485);
FORCEPROP 1 LASTPIN (2025 2475) BN 5
J 0
(2013 2483);
DISPLAY 0.680851 (2013 2483);
PAINT GREEN (2013 2483);
FORCEPROP 2 LAST CDS_LIB standard
J 0
(2075 2475);
DISPLAY INVISIBLE (2075 2475);
FORCEPROP 1 LAST BODY_TYPE PLUMBING
J 0
(2075 2525);
DISPLAY 0.872340 (2075 2525);
PAINT GREEN (2075 2525);
DISPLAY INVISIBLE (2075 2525);
FORCEPROP 1 LAST HDL_TAP TRUE
J 0
(2400 2350);
DISPLAY 0.872340 (2400 2350);
DISPLAY INVISIBLE (2400 2350);
FORCEPROP 1 LAST PATH I144
J 0
(2073 2475);
DISPLAY 0.872340 (2073 2475);
PAINT GREEN (2073 2475);
DISPLAY INVISIBLE (2073 2475);
FORCEADD TAP..1
(1900 2725);
FORCEPROP 3 LASTPIN (1850 2725) SIG_NAME M_H_CPU0_SB_DQS_DP<7>
J 0
(1860 2735);
DISPLAY 0.659574 (1860 2735);
PAINT MONO (1860 2735);
DISPLAY INVISIBLE (1860 2735);
FORCEPROP 1 LASTPIN (1850 2725) BN 7
J 0
(1838 2733);
DISPLAY 0.680851 (1838 2733);
PAINT GREEN (1838 2733);
FORCEPROP 2 LAST CDS_LIB standard
J 0
(1900 2725);
DISPLAY INVISIBLE (1900 2725);
FORCEPROP 1 LAST BODY_TYPE PLUMBING
J 0
(1900 2775);
DISPLAY 0.872340 (1900 2775);
PAINT GREEN (1900 2775);
DISPLAY INVISIBLE (1900 2775);
FORCEPROP 1 LAST HDL_TAP TRUE
J 0
(2225 2600);
DISPLAY 0.872340 (2225 2600);
DISPLAY INVISIBLE (2225 2600);
FORCEPROP 1 LAST PATH I145
J 0
(1898 2725);
DISPLAY 0.872340 (1898 2725);
PAINT GREEN (1898 2725);
DISPLAY INVISIBLE (1898 2725);
FORCEADD TAP..1
(1900 2825);
FORCEPROP 3 LASTPIN (1850 2825) SIG_NAME M_H_CPU0_SB_DQS_DP<8>
J 0
(1860 2835);
DISPLAY 0.659574 (1860 2835);
PAINT MONO (1860 2835);
DISPLAY INVISIBLE (1860 2835);
FORCEPROP 1 LASTPIN (1850 2825) BN 8
J 0
(1838 2833);
DISPLAY 0.680851 (1838 2833);
PAINT GREEN (1838 2833);
FORCEPROP 2 LAST CDS_LIB standard
J 0
(1900 2825);
DISPLAY INVISIBLE (1900 2825);
FORCEPROP 1 LAST BODY_TYPE PLUMBING
J 0
(1900 2875);
DISPLAY 0.872340 (1900 2875);
PAINT GREEN (1900 2875);
DISPLAY INVISIBLE (1900 2875);
FORCEPROP 1 LAST HDL_TAP TRUE
J 0
(2225 2700);
DISPLAY 0.872340 (2225 2700);
DISPLAY INVISIBLE (2225 2700);
FORCEPROP 1 LAST PATH I146
J 0
(1898 2825);
DISPLAY 0.872340 (1898 2825);
PAINT GREEN (1898 2825);
DISPLAY INVISIBLE (1898 2825);
FORCEADD TAP..1
(1900 2925);
FORCEPROP 3 LASTPIN (1850 2925) SIG_NAME M_H_CPU0_SB_DQS_DP<9>
J 0
(1860 2935);
DISPLAY 0.659574 (1860 2935);
PAINT MONO (1860 2935);
DISPLAY INVISIBLE (1860 2935);
FORCEPROP 1 LASTPIN (1850 2925) BN 9
J 0
(1838 2933);
DISPLAY 0.680851 (1838 2933);
PAINT GREEN (1838 2933);
FORCEPROP 2 LAST CDS_LIB standard
J 0
(1900 2925);
DISPLAY INVISIBLE (1900 2925);
FORCEPROP 1 LAST BODY_TYPE PLUMBING
J 0
(1900 2975);
DISPLAY 0.872340 (1900 2975);
PAINT GREEN (1900 2975);
DISPLAY INVISIBLE (1900 2975);
FORCEPROP 1 LAST HDL_TAP TRUE
J 0
(2225 2800);
DISPLAY 0.872340 (2225 2800);
DISPLAY INVISIBLE (2225 2800);
FORCEPROP 1 LAST PATH I147
J 0
(1898 2925);
DISPLAY 0.872340 (1898 2925);
PAINT GREEN (1898 2925);
DISPLAY INVISIBLE (1898 2925);
FORCEADD TAP..1
(2075 2775);
FORCEPROP 3 LASTPIN (2025 2775) SIG_NAME M_H_CPU0_SB_DQS_DN<8>
J 0
(2035 2785);
DISPLAY 0.659574 (2035 2785);
PAINT MONO (2035 2785);
DISPLAY INVISIBLE (2035 2785);
FORCEPROP 1 LASTPIN (2025 2775) BN 8
J 0
(2013 2783);
DISPLAY 0.680851 (2013 2783);
PAINT GREEN (2013 2783);
FORCEPROP 2 LAST CDS_LIB standard
J 0
(2075 2775);
DISPLAY INVISIBLE (2075 2775);
FORCEPROP 1 LAST BODY_TYPE PLUMBING
J 0
(2075 2825);
DISPLAY 0.872340 (2075 2825);
PAINT GREEN (2075 2825);
DISPLAY INVISIBLE (2075 2825);
FORCEPROP 1 LAST HDL_TAP TRUE
J 0
(2400 2650);
DISPLAY 0.872340 (2400 2650);
DISPLAY INVISIBLE (2400 2650);
FORCEPROP 1 LAST PATH I148
J 0
(2073 2775);
DISPLAY 0.872340 (2073 2775);
PAINT GREEN (2073 2775);
DISPLAY INVISIBLE (2073 2775);
FORCEADD TAP..1
(2075 2875);
FORCEPROP 3 LASTPIN (2025 2875) SIG_NAME M_H_CPU0_SB_DQS_DN<9>
J 0
(2035 2885);
DISPLAY 0.659574 (2035 2885);
PAINT MONO (2035 2885);
DISPLAY INVISIBLE (2035 2885);
FORCEPROP 1 LASTPIN (2025 2875) BN 9
J 0
(2013 2883);
DISPLAY 0.680851 (2013 2883);
PAINT GREEN (2013 2883);
FORCEPROP 2 LAST CDS_LIB standard
J 0
(2075 2875);
DISPLAY INVISIBLE (2075 2875);
FORCEPROP 1 LAST BODY_TYPE PLUMBING
J 0
(2075 2925);
DISPLAY 0.872340 (2075 2925);
PAINT GREEN (2075 2925);
DISPLAY INVISIBLE (2075 2925);
FORCEPROP 1 LAST HDL_TAP TRUE
J 0
(2400 2750);
DISPLAY 0.872340 (2400 2750);
DISPLAY INVISIBLE (2400 2750);
FORCEPROP 1 LAST PATH I149
J 0
(2073 2875);
DISPLAY 0.872340 (2073 2875);
PAINT GREEN (2073 2875);
DISPLAY INVISIBLE (2073 2875);
FORCEADD OFFPAGE..1
(-3425 2875);
FORCEPROP 2 LAST $XR0 27 
J 0
(-3646 2875);
DISPLAY 0.638298 (-3646 2875);
PAINT MONO (-3646 2875);
FORCEPROP 2 LAST CDS_LIB standard
J 0
(-3425 2875);
PAINT MONO (-3425 2875);
DISPLAY INVISIBLE (-3425 2875);
FORCEPROP 1 LAST OFFPAGE TRUE
J 0
(-3100 2750);
DISPLAY 0.872340 (-3100 2750);
DISPLAY INVISIBLE (-3100 2750);
FORCEPROP 1 LAST COMMENT_BODY TRUE
J 0
(-3300 2775);
DISPLAY 0.872340 (-3300 2775);
PAINT GREEN (-3300 2775);
DISPLAY INVISIBLE (-3300 2775);
FORCEPROP 2 LAST PATH I15
J 0
(-3375 2950);
DISPLAY 1.021277 (-3375 2950);
DISPLAY INVISIBLE (-3375 2950);
FORCEADD TAP..1
(1900 3075);
FORCEPROP 3 LASTPIN (1850 3075) SIG_NAME M_H_CPU0_SA_DQS_DP<0>
J 0
(1860 3085);
DISPLAY 0.659574 (1860 3085);
PAINT MONO (1860 3085);
DISPLAY INVISIBLE (1860 3085);
FORCEPROP 1 LASTPIN (1850 3075) BN 0
J 0
(1838 3083);
DISPLAY 0.680851 (1838 3083);
PAINT GREEN (1838 3083);
FORCEPROP 2 LAST CDS_LIB standard
J 0
(1900 3075);
PAINT MONO (1900 3075);
DISPLAY INVISIBLE (1900 3075);
FORCEPROP 1 LAST BODY_TYPE PLUMBING
J 0
(1900 3125);
DISPLAY 0.872340 (1900 3125);
PAINT GREEN (1900 3125);
DISPLAY INVISIBLE (1900 3125);
FORCEPROP 1 LAST HDL_TAP TRUE
J 0
(2225 2950);
DISPLAY 0.872340 (2225 2950);
DISPLAY INVISIBLE (2225 2950);
FORCEPROP 1 LAST PATH I150
J 0
(1898 3075);
DISPLAY 0.872340 (1898 3075);
PAINT GREEN (1898 3075);
DISPLAY INVISIBLE (1898 3075);
FORCEADD TAP..1
(1900 3175);
FORCEPROP 3 LASTPIN (1850 3175) SIG_NAME M_H_CPU0_SA_DQS_DP<1>
J 0
(1860 3185);
DISPLAY 0.659574 (1860 3185);
PAINT MONO (1860 3185);
DISPLAY INVISIBLE (1860 3185);
FORCEPROP 1 LASTPIN (1850 3175) BN 1
J 0
(1838 3183);
DISPLAY 0.680851 (1838 3183);
PAINT GREEN (1838 3183);
FORCEPROP 2 LAST CDS_LIB standard
J 0
(1900 3175);
DISPLAY INVISIBLE (1900 3175);
FORCEPROP 1 LAST BODY_TYPE PLUMBING
J 0
(1900 3225);
DISPLAY 0.872340 (1900 3225);
PAINT GREEN (1900 3225);
DISPLAY INVISIBLE (1900 3225);
FORCEPROP 1 LAST HDL_TAP TRUE
J 0
(2225 3050);
DISPLAY 0.872340 (2225 3050);
DISPLAY INVISIBLE (2225 3050);
FORCEPROP 1 LAST PATH I151
J 0
(1898 3175);
DISPLAY 0.872340 (1898 3175);
PAINT GREEN (1898 3175);
DISPLAY INVISIBLE (1898 3175);
FORCEADD TAP..1
(2075 3025);
FORCEPROP 3 LASTPIN (2025 3025) SIG_NAME M_H_CPU0_SA_DQS_DN<0>
J 0
(2035 3035);
DISPLAY 0.659574 (2035 3035);
PAINT MONO (2035 3035);
DISPLAY INVISIBLE (2035 3035);
FORCEPROP 1 LASTPIN (2025 3025) BN 0
J 0
(2013 3033);
DISPLAY 0.680851 (2013 3033);
PAINT GREEN (2013 3033);
FORCEPROP 2 LAST CDS_LIB standard
J 0
(2075 3025);
PAINT MONO (2075 3025);
DISPLAY INVISIBLE (2075 3025);
FORCEPROP 1 LAST BODY_TYPE PLUMBING
J 0
(2075 3075);
DISPLAY 0.872340 (2075 3075);
PAINT GREEN (2075 3075);
DISPLAY INVISIBLE (2075 3075);
FORCEPROP 1 LAST HDL_TAP TRUE
J 0
(2400 2900);
DISPLAY 0.872340 (2400 2900);
DISPLAY INVISIBLE (2400 2900);
FORCEPROP 1 LAST PATH I152
J 0
(2073 3025);
DISPLAY 0.872340 (2073 3025);
PAINT GREEN (2073 3025);
DISPLAY INVISIBLE (2073 3025);
FORCEADD TAP..1
(2075 3125);
FORCEPROP 3 LASTPIN (2025 3125) SIG_NAME M_H_CPU0_SA_DQS_DN<1>
J 0
(2035 3135);
DISPLAY 0.659574 (2035 3135);
PAINT MONO (2035 3135);
DISPLAY INVISIBLE (2035 3135);
FORCEPROP 1 LASTPIN (2025 3125) BN 1
J 0
(2013 3133);
DISPLAY 0.680851 (2013 3133);
PAINT GREEN (2013 3133);
FORCEPROP 2 LAST CDS_LIB standard
J 0
(2075 3125);
DISPLAY INVISIBLE (2075 3125);
FORCEPROP 1 LAST BODY_TYPE PLUMBING
J 0
(2075 3175);
DISPLAY 0.872340 (2075 3175);
PAINT GREEN (2075 3175);
DISPLAY INVISIBLE (2075 3175);
FORCEPROP 1 LAST HDL_TAP TRUE
J 0
(2400 3000);
DISPLAY 0.872340 (2400 3000);
DISPLAY INVISIBLE (2400 3000);
FORCEPROP 1 LAST PATH I153
J 0
(2073 3125);
DISPLAY 0.872340 (2073 3125);
PAINT GREEN (2073 3125);
DISPLAY INVISIBLE (2073 3125);
FORCEADD TAP..1
(1900 3275);
FORCEPROP 3 LASTPIN (1850 3275) SIG_NAME M_H_CPU0_SA_DQS_DP<2>
J 0
(1860 3285);
DISPLAY 0.659574 (1860 3285);
PAINT MONO (1860 3285);
DISPLAY INVISIBLE (1860 3285);
FORCEPROP 1 LASTPIN (1850 3275) BN 2
J 0
(1838 3283);
DISPLAY 0.680851 (1838 3283);
PAINT GREEN (1838 3283);
FORCEPROP 2 LAST CDS_LIB standard
J 0
(1900 3275);
DISPLAY INVISIBLE (1900 3275);
FORCEPROP 1 LAST BODY_TYPE PLUMBING
J 0
(1900 3325);
DISPLAY 0.872340 (1900 3325);
PAINT GREEN (1900 3325);
DISPLAY INVISIBLE (1900 3325);
FORCEPROP 1 LAST HDL_TAP TRUE
J 0
(2225 3150);
DISPLAY 0.872340 (2225 3150);
DISPLAY INVISIBLE (2225 3150);
FORCEPROP 1 LAST PATH I154
J 0
(1898 3275);
DISPLAY 0.872340 (1898 3275);
PAINT GREEN (1898 3275);
DISPLAY INVISIBLE (1898 3275);
FORCEADD TAP..1
(1900 3375);
FORCEPROP 3 LASTPIN (1850 3375) SIG_NAME M_H_CPU0_SA_DQS_DP<3>
J 0
(1860 3385);
DISPLAY 0.659574 (1860 3385);
PAINT MONO (1860 3385);
DISPLAY INVISIBLE (1860 3385);
FORCEPROP 1 LASTPIN (1850 3375) BN 3
J 0
(1838 3383);
DISPLAY 0.680851 (1838 3383);
PAINT GREEN (1838 3383);
FORCEPROP 2 LAST CDS_LIB standard
J 0
(1900 3375);
PAINT MONO (1900 3375);
DISPLAY INVISIBLE (1900 3375);
FORCEPROP 1 LAST BODY_TYPE PLUMBING
J 0
(1900 3425);
DISPLAY 0.872340 (1900 3425);
PAINT GREEN (1900 3425);
DISPLAY INVISIBLE (1900 3425);
FORCEPROP 1 LAST HDL_TAP TRUE
J 0
(2225 3250);
DISPLAY 0.872340 (2225 3250);
DISPLAY INVISIBLE (2225 3250);
FORCEPROP 1 LAST PATH I155
J 0
(1898 3375);
DISPLAY 0.872340 (1898 3375);
PAINT GREEN (1898 3375);
DISPLAY INVISIBLE (1898 3375);
FORCEADD TAP..1
(2075 3225);
FORCEPROP 3 LASTPIN (2025 3225) SIG_NAME M_H_CPU0_SA_DQS_DN<2>
J 0
(2035 3235);
DISPLAY 0.659574 (2035 3235);
PAINT MONO (2035 3235);
DISPLAY INVISIBLE (2035 3235);
FORCEPROP 1 LASTPIN (2025 3225) BN 2
J 0
(2013 3233);
DISPLAY 0.680851 (2013 3233);
PAINT GREEN (2013 3233);
FORCEPROP 2 LAST CDS_LIB standard
J 0
(2075 3225);
DISPLAY INVISIBLE (2075 3225);
FORCEPROP 1 LAST BODY_TYPE PLUMBING
J 0
(2075 3275);
DISPLAY 0.872340 (2075 3275);
PAINT GREEN (2075 3275);
DISPLAY INVISIBLE (2075 3275);
FORCEPROP 1 LAST HDL_TAP TRUE
J 0
(2400 3100);
DISPLAY 0.872340 (2400 3100);
DISPLAY INVISIBLE (2400 3100);
FORCEPROP 1 LAST PATH I156
J 0
(2073 3225);
DISPLAY 0.872340 (2073 3225);
PAINT GREEN (2073 3225);
DISPLAY INVISIBLE (2073 3225);
FORCEADD TAP..1
(2075 3325);
FORCEPROP 3 LASTPIN (2025 3325) SIG_NAME M_H_CPU0_SA_DQS_DN<3>
J 0
(2035 3335);
DISPLAY 0.659574 (2035 3335);
PAINT MONO (2035 3335);
DISPLAY INVISIBLE (2035 3335);
FORCEPROP 1 LASTPIN (2025 3325) BN 3
J 0
(2013 3333);
DISPLAY 0.680851 (2013 3333);
PAINT GREEN (2013 3333);
FORCEPROP 2 LAST CDS_LIB standard
J 0
(2075 3325);
PAINT MONO (2075 3325);
DISPLAY INVISIBLE (2075 3325);
FORCEPROP 1 LAST BODY_TYPE PLUMBING
J 0
(2075 3375);
DISPLAY 0.872340 (2075 3375);
PAINT GREEN (2075 3375);
DISPLAY INVISIBLE (2075 3375);
FORCEPROP 1 LAST HDL_TAP TRUE
J 0
(2400 3200);
DISPLAY 0.872340 (2400 3200);
DISPLAY INVISIBLE (2400 3200);
FORCEPROP 1 LAST PATH I157
J 0
(2073 3325);
DISPLAY 0.872340 (2073 3325);
PAINT GREEN (2073 3325);
DISPLAY INVISIBLE (2073 3325);
FORCEADD TAP..1
(2075 3425);
FORCEPROP 3 LASTPIN (2025 3425) SIG_NAME M_H_CPU0_SA_DQS_DN<4>
J 0
(2035 3435);
DISPLAY 0.659574 (2035 3435);
PAINT MONO (2035 3435);
DISPLAY INVISIBLE (2035 3435);
FORCEPROP 1 LASTPIN (2025 3425) BN 4
J 0
(2013 3433);
DISPLAY 0.680851 (2013 3433);
PAINT GREEN (2013 3433);
FORCEPROP 2 LAST CDS_LIB standard
J 0
(2075 3425);
PAINT MONO (2075 3425);
DISPLAY INVISIBLE (2075 3425);
FORCEPROP 1 LAST BODY_TYPE PLUMBING
J 0
(2075 3475);
DISPLAY 0.872340 (2075 3475);
PAINT GREEN (2075 3475);
DISPLAY INVISIBLE (2075 3475);
FORCEPROP 1 LAST HDL_TAP TRUE
J 0
(2400 3300);
DISPLAY 0.872340 (2400 3300);
DISPLAY INVISIBLE (2400 3300);
FORCEPROP 1 LAST PATH I158
J 0
(2073 3425);
DISPLAY 0.872340 (2073 3425);
PAINT GREEN (2073 3425);
DISPLAY INVISIBLE (2073 3425);
FORCEADD TAP..1
(1900 3475);
FORCEPROP 3 LASTPIN (1850 3475) SIG_NAME M_H_CPU0_SA_DQS_DP<4>
J 0
(1860 3485);
DISPLAY 0.659574 (1860 3485);
PAINT MONO (1860 3485);
DISPLAY INVISIBLE (1860 3485);
FORCEPROP 1 LASTPIN (1850 3475) BN 4
J 0
(1838 3483);
DISPLAY 0.680851 (1838 3483);
PAINT GREEN (1838 3483);
FORCEPROP 2 LAST CDS_LIB standard
J 0
(1900 3475);
PAINT MONO (1900 3475);
DISPLAY INVISIBLE (1900 3475);
FORCEPROP 1 LAST BODY_TYPE PLUMBING
J 0
(1900 3525);
DISPLAY 0.872340 (1900 3525);
PAINT GREEN (1900 3525);
DISPLAY INVISIBLE (1900 3525);
FORCEPROP 1 LAST HDL_TAP TRUE
J 0
(2225 3350);
DISPLAY 0.872340 (2225 3350);
DISPLAY INVISIBLE (2225 3350);
FORCEPROP 1 LAST PATH I159
J 0
(1898 3475);
DISPLAY 0.872340 (1898 3475);
PAINT GREEN (1898 3475);
DISPLAY INVISIBLE (1898 3475);
FORCEADD OFFPAGE..1
(-3425 2825);
FORCEPROP 2 LAST $XR0 27 
J 0
(-3646 2825);
DISPLAY 0.638298 (-3646 2825);
PAINT MONO (-3646 2825);
FORCEPROP 2 LAST CDS_LIB standard
J 0
(-3425 2825);
PAINT MONO (-3425 2825);
DISPLAY INVISIBLE (-3425 2825);
FORCEPROP 1 LAST OFFPAGE TRUE
J 0
(-3100 2700);
DISPLAY 0.872340 (-3100 2700);
DISPLAY INVISIBLE (-3100 2700);
FORCEPROP 1 LAST COMMENT_BODY TRUE
J 0
(-3300 2725);
DISPLAY 0.872340 (-3300 2725);
PAINT GREEN (-3300 2725);
DISPLAY INVISIBLE (-3300 2725);
FORCEPROP 2 LAST PATH I16
J 0
(-3375 2900);
DISPLAY 1.021277 (-3375 2900);
DISPLAY INVISIBLE (-3375 2900);
FORCEADD TAP..1
(1900 3575);
FORCEPROP 3 LASTPIN (1850 3575) SIG_NAME M_H_CPU0_SA_DQS_DP<5>
J 0
(1860 3585);
DISPLAY 0.659574 (1860 3585);
PAINT MONO (1860 3585);
DISPLAY INVISIBLE (1860 3585);
FORCEPROP 1 LASTPIN (1850 3575) BN 5
J 0
(1838 3583);
DISPLAY 0.680851 (1838 3583);
PAINT GREEN (1838 3583);
FORCEPROP 2 LAST CDS_LIB standard
J 0
(1900 3575);
DISPLAY INVISIBLE (1900 3575);
FORCEPROP 1 LAST BODY_TYPE PLUMBING
J 0
(1900 3625);
DISPLAY 0.872340 (1900 3625);
PAINT GREEN (1900 3625);
DISPLAY INVISIBLE (1900 3625);
FORCEPROP 1 LAST HDL_TAP TRUE
J 0
(2225 3450);
DISPLAY 0.872340 (2225 3450);
DISPLAY INVISIBLE (2225 3450);
FORCEPROP 1 LAST PATH I160
J 0
(1898 3575);
DISPLAY 0.872340 (1898 3575);
PAINT GREEN (1898 3575);
DISPLAY INVISIBLE (1898 3575);
FORCEADD TAP..1
(1900 3675);
FORCEPROP 3 LASTPIN (1850 3675) SIG_NAME M_H_CPU0_SA_DQS_DP<6>
J 0
(1860 3685);
DISPLAY 0.659574 (1860 3685);
PAINT MONO (1860 3685);
DISPLAY INVISIBLE (1860 3685);
FORCEPROP 1 LASTPIN (1850 3675) BN 6
J 0
(1838 3683);
DISPLAY 0.680851 (1838 3683);
PAINT GREEN (1838 3683);
FORCEPROP 2 LAST CDS_LIB standard
J 0
(1900 3675);
DISPLAY INVISIBLE (1900 3675);
FORCEPROP 1 LAST BODY_TYPE PLUMBING
J 0
(1900 3725);
DISPLAY 0.872340 (1900 3725);
PAINT GREEN (1900 3725);
DISPLAY INVISIBLE (1900 3725);
FORCEPROP 1 LAST HDL_TAP TRUE
J 0
(2225 3550);
DISPLAY 0.872340 (2225 3550);
DISPLAY INVISIBLE (2225 3550);
FORCEPROP 1 LAST PATH I161
J 0
(1898 3675);
DISPLAY 0.872340 (1898 3675);
PAINT GREEN (1898 3675);
DISPLAY INVISIBLE (1898 3675);
FORCEADD TAP..1
(2075 3625);
FORCEPROP 3 LASTPIN (2025 3625) SIG_NAME M_H_CPU0_SA_DQS_DN<6>
J 0
(2035 3635);
DISPLAY 0.659574 (2035 3635);
PAINT MONO (2035 3635);
DISPLAY INVISIBLE (2035 3635);
FORCEPROP 1 LASTPIN (2025 3625) BN 6
J 0
(2013 3633);
DISPLAY 0.680851 (2013 3633);
PAINT GREEN (2013 3633);
FORCEPROP 2 LAST CDS_LIB standard
J 0
(2075 3625);
DISPLAY INVISIBLE (2075 3625);
FORCEPROP 1 LAST BODY_TYPE PLUMBING
J 0
(2075 3675);
DISPLAY 0.872340 (2075 3675);
PAINT GREEN (2075 3675);
DISPLAY INVISIBLE (2075 3675);
FORCEPROP 1 LAST HDL_TAP TRUE
J 0
(2400 3500);
DISPLAY 0.872340 (2400 3500);
DISPLAY INVISIBLE (2400 3500);
FORCEPROP 1 LAST PATH I162
J 0
(2073 3625);
DISPLAY 0.872340 (2073 3625);
PAINT GREEN (2073 3625);
DISPLAY INVISIBLE (2073 3625);
FORCEADD TAP..1
(2075 3525);
FORCEPROP 3 LASTPIN (2025 3525) SIG_NAME M_H_CPU0_SA_DQS_DN<5>
J 0
(2035 3535);
DISPLAY 0.659574 (2035 3535);
PAINT MONO (2035 3535);
DISPLAY INVISIBLE (2035 3535);
FORCEPROP 1 LASTPIN (2025 3525) BN 5
J 0
(2013 3533);
DISPLAY 0.680851 (2013 3533);
PAINT GREEN (2013 3533);
FORCEPROP 2 LAST CDS_LIB standard
J 0
(2075 3525);
DISPLAY INVISIBLE (2075 3525);
FORCEPROP 1 LAST BODY_TYPE PLUMBING
J 0
(2075 3575);
DISPLAY 0.872340 (2075 3575);
PAINT GREEN (2075 3575);
DISPLAY INVISIBLE (2075 3575);
FORCEPROP 1 LAST HDL_TAP TRUE
J 0
(2400 3400);
DISPLAY 0.872340 (2400 3400);
DISPLAY INVISIBLE (2400 3400);
FORCEPROP 1 LAST PATH I163
J 0
(2073 3525);
DISPLAY 0.872340 (2073 3525);
PAINT GREEN (2073 3525);
DISPLAY INVISIBLE (2073 3525);
FORCEADD OFFPAGE..2
(3025 2950);
FORCEPROP 2 LAST $XR1 97 
J 0
(3304 2950);
DISPLAY 0.638298 (3304 2950);
PAINT MONO (3304 2950);
FORCEPROP 2 LAST $XR0 27 
J 0
(3214 2950);
DISPLAY 0.638298 (3214 2950);
PAINT MONO (3214 2950);
FORCEPROP 2 LAST CDS_LIB standard
J 0
(3025 2950);
PAINT MONO (3025 2950);
DISPLAY INVISIBLE (3025 2950);
FORCEPROP 1 LAST OFFPAGE TRUE
J 0
(3350 2825);
DISPLAY 1.170213 (3350 2825);
PAINT GREEN (3350 2825);
DISPLAY INVISIBLE (3350 2825);
FORCEPROP 1 LAST COMMENT_BODY TRUE
J 0
(2980 2855);
DISPLAY 1.170213 (2980 2855);
PAINT GREEN (2980 2855);
DISPLAY INVISIBLE (2980 2855);
FORCEPROP 2 LAST PATH I164
J 0
(3200 3025);
DISPLAY 1.021277 (3200 3025);
DISPLAY INVISIBLE (3200 3025);
FORCEADD OFFPAGE..2
(3025 2900);
FORCEPROP 2 LAST $XR1 97 
J 0
(3304 2900);
DISPLAY 0.638298 (3304 2900);
PAINT MONO (3304 2900);
FORCEPROP 2 LAST $XR0 27 
J 0
(3214 2900);
DISPLAY 0.638298 (3214 2900);
PAINT MONO (3214 2900);
FORCEPROP 2 LAST CDS_LIB standard
J 0
(3025 2900);
PAINT MONO (3025 2900);
DISPLAY INVISIBLE (3025 2900);
FORCEPROP 1 LAST OFFPAGE TRUE
J 0
(3350 2775);
DISPLAY 1.170213 (3350 2775);
PAINT GREEN (3350 2775);
DISPLAY INVISIBLE (3350 2775);
FORCEPROP 1 LAST COMMENT_BODY TRUE
J 0
(2980 2805);
DISPLAY 1.170213 (2980 2805);
PAINT GREEN (2980 2805);
DISPLAY INVISIBLE (2980 2805);
FORCEPROP 2 LAST PATH I165
J 0
(3200 2975);
DISPLAY 1.021277 (3200 2975);
DISPLAY INVISIBLE (3200 2975);
FORCEADD OFFPAGE..3
(-25 4000);
FORCEPROP 2 LAST $XR1 97 
J 0
(279 4000);
DISPLAY 0.638298 (279 4000);
PAINT MONO (279 4000);
FORCEPROP 2 LAST $XR0 27 
J 0
(189 4000);
DISPLAY 0.638298 (189 4000);
PAINT MONO (189 4000);
FORCEPROP 2 LAST CDS_LIB standard
J 2
(-25 4000);
DISPLAY INVISIBLE (-25 4000);
FORCEPROP 1 LAST OFFPAGE TRUE
J 0
(300 3875);
DISPLAY 0.872340 (300 3875);
DISPLAY INVISIBLE (300 3875);
FORCEPROP 1 LAST COMMENT_BODY TRUE
J 0
(-75 3900);
DISPLAY 0.872340 (-75 3900);
PAINT GREEN (-75 3900);
DISPLAY INVISIBLE (-75 3900);
FORCEPROP 2 LAST PATH I166
J 0
(175 4075);
DISPLAY 1.021277 (175 4075);
DISPLAY INVISIBLE (175 4075);
FORCEADD TAP..1
(1900 3775);
FORCEPROP 3 LASTPIN (1850 3775) SIG_NAME M_H_CPU0_SA_DQS_DP<7>
J 0
(1860 3785);
DISPLAY 0.659574 (1860 3785);
PAINT MONO (1860 3785);
DISPLAY INVISIBLE (1860 3785);
FORCEPROP 1 LASTPIN (1850 3775) BN 7
J 0
(1838 3783);
DISPLAY 0.680851 (1838 3783);
PAINT GREEN (1838 3783);
FORCEPROP 2 LAST CDS_LIB standard
J 0
(1900 3775);
DISPLAY INVISIBLE (1900 3775);
FORCEPROP 1 LAST BODY_TYPE PLUMBING
J 0
(1900 3825);
DISPLAY 0.872340 (1900 3825);
PAINT GREEN (1900 3825);
DISPLAY INVISIBLE (1900 3825);
FORCEPROP 1 LAST HDL_TAP TRUE
J 0
(2225 3650);
DISPLAY 0.872340 (2225 3650);
DISPLAY INVISIBLE (2225 3650);
FORCEPROP 1 LAST PATH I167
J 0
(1898 3775);
DISPLAY 0.872340 (1898 3775);
PAINT GREEN (1898 3775);
DISPLAY INVISIBLE (1898 3775);
FORCEADD TAP..1
(1900 3975);
FORCEPROP 3 LASTPIN (1850 3975) SIG_NAME M_H_CPU0_SA_DQS_DP<9>
J 0
(1860 3985);
DISPLAY 0.659574 (1860 3985);
PAINT MONO (1860 3985);
DISPLAY INVISIBLE (1860 3985);
FORCEPROP 1 LASTPIN (1850 3975) BN 9
J 0
(1838 3983);
DISPLAY 0.680851 (1838 3983);
PAINT GREEN (1838 3983);
FORCEPROP 2 LAST CDS_LIB standard
J 0
(1900 3975);
DISPLAY INVISIBLE (1900 3975);
FORCEPROP 1 LAST BODY_TYPE PLUMBING
J 0
(1900 4025);
DISPLAY 0.872340 (1900 4025);
PAINT GREEN (1900 4025);
DISPLAY INVISIBLE (1900 4025);
FORCEPROP 1 LAST HDL_TAP TRUE
J 0
(2225 3850);
DISPLAY 0.872340 (2225 3850);
DISPLAY INVISIBLE (2225 3850);
FORCEPROP 1 LAST PATH I168
J 0
(1898 3975);
DISPLAY 0.872340 (1898 3975);
PAINT GREEN (1898 3975);
DISPLAY INVISIBLE (1898 3975);
FORCEADD TAP..1
(1900 3875);
FORCEPROP 3 LASTPIN (1850 3875) SIG_NAME M_H_CPU0_SA_DQS_DP<8>
J 0
(1860 3885);
DISPLAY 0.659574 (1860 3885);
PAINT MONO (1860 3885);
DISPLAY INVISIBLE (1860 3885);
FORCEPROP 1 LASTPIN (1850 3875) BN 8
J 0
(1838 3883);
DISPLAY 0.680851 (1838 3883);
PAINT GREEN (1838 3883);
FORCEPROP 2 LAST CDS_LIB standard
J 0
(1900 3875);
DISPLAY INVISIBLE (1900 3875);
FORCEPROP 1 LAST BODY_TYPE PLUMBING
J 0
(1900 3925);
DISPLAY 0.872340 (1900 3925);
PAINT GREEN (1900 3925);
DISPLAY INVISIBLE (1900 3925);
FORCEPROP 1 LAST HDL_TAP TRUE
J 0
(2225 3750);
DISPLAY 0.872340 (2225 3750);
DISPLAY INVISIBLE (2225 3750);
FORCEPROP 1 LAST PATH I169
J 0
(1898 3875);
DISPLAY 0.872340 (1898 3875);
PAINT GREEN (1898 3875);
DISPLAY INVISIBLE (1898 3875);
FORCEADD OFFPAGE..1
(-3425 2975);
FORCEPROP 2 LAST $XR0 27 
J 0
(-3646 2975);
DISPLAY 0.638298 (-3646 2975);
PAINT MONO (-3646 2975);
FORCEPROP 2 LAST CDS_LIB standard
J 0
(-3425 2975);
PAINT MONO (-3425 2975);
DISPLAY INVISIBLE (-3425 2975);
FORCEPROP 1 LAST OFFPAGE TRUE
J 0
(-3100 2850);
DISPLAY 0.872340 (-3100 2850);
DISPLAY INVISIBLE (-3100 2850);
FORCEPROP 1 LAST COMMENT_BODY TRUE
J 0
(-3300 2875);
DISPLAY 0.872340 (-3300 2875);
PAINT GREEN (-3300 2875);
DISPLAY INVISIBLE (-3300 2875);
FORCEPROP 2 LAST PATH I17
J 0
(-3375 3050);
DISPLAY 1.021277 (-3375 3050);
DISPLAY INVISIBLE (-3375 3050);
FORCEADD TAP..1
(2075 3725);
FORCEPROP 3 LASTPIN (2025 3725) SIG_NAME M_H_CPU0_SA_DQS_DN<7>
J 0
(2035 3735);
DISPLAY 0.659574 (2035 3735);
PAINT MONO (2035 3735);
DISPLAY INVISIBLE (2035 3735);
FORCEPROP 1 LASTPIN (2025 3725) BN 7
J 0
(2013 3733);
DISPLAY 0.680851 (2013 3733);
PAINT GREEN (2013 3733);
FORCEPROP 2 LAST CDS_LIB standard
J 0
(2075 3725);
DISPLAY INVISIBLE (2075 3725);
FORCEPROP 1 LAST BODY_TYPE PLUMBING
J 0
(2075 3775);
DISPLAY 0.872340 (2075 3775);
PAINT GREEN (2075 3775);
DISPLAY INVISIBLE (2075 3775);
FORCEPROP 1 LAST HDL_TAP TRUE
J 0
(2400 3600);
DISPLAY 0.872340 (2400 3600);
DISPLAY INVISIBLE (2400 3600);
FORCEPROP 1 LAST PATH I170
J 0
(2073 3725);
DISPLAY 0.872340 (2073 3725);
PAINT GREEN (2073 3725);
DISPLAY INVISIBLE (2073 3725);
FORCEADD TAP..1
(2075 3825);
FORCEPROP 3 LASTPIN (2025 3825) SIG_NAME M_H_CPU0_SA_DQS_DN<8>
J 0
(2035 3835);
DISPLAY 0.659574 (2035 3835);
PAINT MONO (2035 3835);
DISPLAY INVISIBLE (2035 3835);
FORCEPROP 1 LASTPIN (2025 3825) BN 8
J 0
(2013 3833);
DISPLAY 0.680851 (2013 3833);
PAINT GREEN (2013 3833);
FORCEPROP 2 LAST CDS_LIB standard
J 0
(2075 3825);
DISPLAY INVISIBLE (2075 3825);
FORCEPROP 1 LAST BODY_TYPE PLUMBING
J 0
(2075 3875);
DISPLAY 0.872340 (2075 3875);
PAINT GREEN (2075 3875);
DISPLAY INVISIBLE (2075 3875);
FORCEPROP 1 LAST HDL_TAP TRUE
J 0
(2400 3700);
DISPLAY 0.872340 (2400 3700);
DISPLAY INVISIBLE (2400 3700);
FORCEPROP 1 LAST PATH I171
J 0
(2073 3825);
DISPLAY 0.872340 (2073 3825);
PAINT GREEN (2073 3825);
DISPLAY INVISIBLE (2073 3825);
FORCEADD TAP..1
(2075 3925);
FORCEPROP 3 LASTPIN (2025 3925) SIG_NAME M_H_CPU0_SA_DQS_DN<9>
J 0
(2035 3935);
DISPLAY 0.659574 (2035 3935);
PAINT MONO (2035 3935);
DISPLAY INVISIBLE (2035 3935);
FORCEPROP 1 LASTPIN (2025 3925) BN 9
J 0
(2013 3933);
DISPLAY 0.680851 (2013 3933);
PAINT GREEN (2013 3933);
FORCEPROP 2 LAST CDS_LIB standard
J 0
(2075 3925);
DISPLAY INVISIBLE (2075 3925);
FORCEPROP 1 LAST BODY_TYPE PLUMBING
J 0
(2075 3975);
DISPLAY 0.872340 (2075 3975);
PAINT GREEN (2075 3975);
DISPLAY INVISIBLE (2075 3975);
FORCEPROP 1 LAST HDL_TAP TRUE
J 0
(2400 3800);
DISPLAY 0.872340 (2400 3800);
DISPLAY INVISIBLE (2400 3800);
FORCEPROP 1 LAST PATH I172
J 0
(2073 3925);
DISPLAY 0.872340 (2073 3925);
PAINT GREEN (2073 3925);
DISPLAY INVISIBLE (2073 3925);
FORCEADD OFFPAGE..2
(3025 3950);
FORCEPROP 2 LAST $XR1 97 
J 0
(3304 3950);
DISPLAY 0.638298 (3304 3950);
PAINT MONO (3304 3950);
FORCEPROP 2 LAST $XR0 27 
J 0
(3214 3950);
DISPLAY 0.638298 (3214 3950);
PAINT MONO (3214 3950);
FORCEPROP 2 LAST CDS_LIB standard
J 0
(3025 3950);
PAINT MONO (3025 3950);
DISPLAY INVISIBLE (3025 3950);
FORCEPROP 1 LAST OFFPAGE TRUE
J 0
(3350 3825);
DISPLAY 1.170213 (3350 3825);
PAINT GREEN (3350 3825);
DISPLAY INVISIBLE (3350 3825);
FORCEPROP 1 LAST COMMENT_BODY TRUE
J 0
(2980 3855);
DISPLAY 1.170213 (2980 3855);
PAINT GREEN (2980 3855);
DISPLAY INVISIBLE (2980 3855);
FORCEPROP 2 LAST PATH I173
J 0
(3200 4025);
DISPLAY 1.021277 (3200 4025);
DISPLAY INVISIBLE (3200 4025);
FORCEADD OFFPAGE..2
(3025 4000);
FORCEPROP 2 LAST $XR1 97 
J 0
(3304 4000);
DISPLAY 0.638298 (3304 4000);
PAINT MONO (3304 4000);
FORCEPROP 2 LAST $XR0 27 
J 0
(3214 4000);
DISPLAY 0.638298 (3214 4000);
PAINT MONO (3214 4000);
FORCEPROP 2 LAST CDS_LIB standard
J 0
(3025 4000);
PAINT MONO (3025 4000);
DISPLAY INVISIBLE (3025 4000);
FORCEPROP 1 LAST OFFPAGE TRUE
J 0
(3350 3875);
DISPLAY 1.170213 (3350 3875);
PAINT GREEN (3350 3875);
DISPLAY INVISIBLE (3350 3875);
FORCEPROP 1 LAST COMMENT_BODY TRUE
J 0
(2980 3905);
DISPLAY 1.170213 (2980 3905);
PAINT GREEN (2980 3905);
DISPLAY INVISIBLE (2980 3905);
FORCEPROP 2 LAST PATH I174
J 0
(3200 4075);
DISPLAY 1.021277 (3200 4075);
DISPLAY INVISIBLE (3200 4075);
FORCEADD VCC_CORE..1
(3575 4525);
FORCEPROP 3 LASTPIN (3575 4475) SIG_NAME P12V_S3_AUX_CPU0_NVDIMM\g
J 0
(3585 4485);
DISPLAY 0.659574 (3585 4485);
PAINT MONO (3585 4485);
DISPLAY INVISIBLE (3585 4485);
FORCEPROP 1 LAST HDL_POWER P12V_S3_AUX_CPU0_NVDIMM
J 1
(3575 4575);
DISPLAY 1.148936 (3575 4575);
PAINT GREEN (3575 4575);
FORCEPROP 2 LAST CDS_LIB logical_power
J 0
(3575 4525);
PAINT MONO (3575 4525);
DISPLAY INVISIBLE (3575 4525);
FORCEPROP 1 LAST PATH I175
J 0
(3625 4550);
DISPLAY 0.872340 (3625 4550);
PAINT AQUA (3625 4550);
DISPLAY INVISIBLE (3625 4550);
FORCEADD SCONN288_ADR50017P130CC..3
(4425 2350);
FORCEPROP 1 LAST PART_NUMBER DFHST8FS461
J 0
(3970 4274);
DISPLAY 0.723404 (3970 4274);
PAINT GREEN (3970 4274);
DISPLAY INVISIBLE (3970 4274);
FORCEPROP 1 LAST MATERIAL IO
J 0
(3970 4147);
DISPLAY 0.723404 (3970 4147);
PAINT GREEN (3970 4147);
FORCEPROP 2 LAST VALUE SCONN288_ADR50017-P130CC
J 0
(3975 4375);
DISPLAY 1.021277 (3975 4375);
FORCEPROP 2 LAST PART_TYPE SMLF
J 0
(3975 4425);
DISPLAY 1.021277 (3975 4425);
FORCEPROP 1 LAST $LOCATION J15
J 0
(3975 4325);
DISPLAY 0.723404 (3975 4325);
PAINT GREEN (3975 4325);
FORCEPROP 0 LASTPIN (5025 725) $PN G1
J 0
(5035 735);
DISPLAY 0.680851 (5035 735);
PAINT MONO (5035 735);
FORCEPROP 0 LASTPIN (5025 675) $PN G2
J 0
(5035 685);
DISPLAY 0.680851 (5035 685);
PAINT MONO (5035 685);
FORCEPROP 0 LASTPIN (5025 625) $PN G3
J 0
(5035 635);
DISPLAY 0.680851 (5035 635);
PAINT MONO (5035 635);
FORCEPROP 0 LASTPIN (3825 3875) $PN 1
J 2
(3815 3885);
DISPLAY 0.680851 (3815 3885);
PAINT MONO (3815 3885);
FORCEPROP 0 LASTPIN (3825 3925) $PN 145
J 2
(3815 3935);
DISPLAY 0.680851 (3815 3935);
PAINT MONO (3815 3935);
FORCEPROP 0 LASTPIN (3825 3975) $PN 146
J 2
(3815 3985);
DISPLAY 0.680851 (3815 3985);
PAINT MONO (3815 3985);
FORCEPROP 0 LASTPIN (5025 825) $PN 6
J 0
(5035 835);
DISPLAY 0.680851 (5035 835);
PAINT MONO (5035 835);
FORCEPROP 0 LASTPIN (5025 875) $PN 8
J 0
(5035 885);
DISPLAY 0.680851 (5035 885);
PAINT MONO (5035 885);
FORCEPROP 0 LASTPIN (5025 925) $PN 10
J 0
(5035 935);
DISPLAY 0.680851 (5035 935);
PAINT MONO (5035 935);
FORCEPROP 0 LASTPIN (5025 975) $PN 13
J 0
(5035 985);
DISPLAY 0.680851 (5035 985);
PAINT MONO (5035 985);
FORCEPROP 0 LASTPIN (5025 1025) $PN 15
J 0
(5035 1035);
DISPLAY 0.680851 (5035 1035);
PAINT MONO (5035 1035);
FORCEPROP 0 LASTPIN (5025 1075) $PN 17
J 0
(5035 1085);
DISPLAY 0.680851 (5035 1085);
PAINT MONO (5035 1085);
FORCEPROP 0 LASTPIN (5025 1125) $PN 19
J 0
(5035 1135);
DISPLAY 0.680851 (5035 1135);
PAINT MONO (5035 1135);
FORCEPROP 0 LASTPIN (5025 1175) $PN 21
J 0
(5035 1185);
DISPLAY 0.680851 (5035 1185);
PAINT MONO (5035 1185);
FORCEPROP 0 LASTPIN (5025 1225) $PN 24
J 0
(5035 1235);
DISPLAY 0.680851 (5035 1235);
PAINT MONO (5035 1235);
FORCEPROP 0 LASTPIN (5025 1275) $PN 26
J 0
(5035 1285);
DISPLAY 0.680851 (5035 1285);
PAINT MONO (5035 1285);
FORCEPROP 0 LASTPIN (5025 1325) $PN 28
J 0
(5035 1335);
DISPLAY 0.680851 (5035 1335);
PAINT MONO (5035 1335);
FORCEPROP 0 LASTPIN (5025 1375) $PN 30
J 0
(5035 1385);
DISPLAY 0.680851 (5035 1385);
PAINT MONO (5035 1385);
FORCEPROP 0 LASTPIN (5025 1425) $PN 32
J 0
(5035 1435);
DISPLAY 0.680851 (5035 1435);
PAINT MONO (5035 1435);
FORCEPROP 0 LASTPIN (5025 1475) $PN 35
J 0
(5035 1485);
DISPLAY 0.680851 (5035 1485);
PAINT MONO (5035 1485);
FORCEPROP 0 LASTPIN (5025 1525) $PN 37
J 0
(5035 1535);
DISPLAY 0.680851 (5035 1535);
PAINT MONO (5035 1535);
FORCEPROP 0 LASTPIN (5025 1575) $PN 39
J 0
(5035 1585);
DISPLAY 0.680851 (5035 1585);
PAINT MONO (5035 1585);
FORCEPROP 0 LASTPIN (5025 1625) $PN 41
J 0
(5035 1635);
DISPLAY 0.680851 (5035 1635);
PAINT MONO (5035 1635);
FORCEPROP 0 LASTPIN (5025 1675) $PN 43
J 0
(5035 1685);
DISPLAY 0.680851 (5035 1685);
PAINT MONO (5035 1685);
FORCEPROP 0 LASTPIN (5025 1725) $PN 46
J 0
(5035 1735);
DISPLAY 0.680851 (5035 1735);
PAINT MONO (5035 1735);
FORCEPROP 0 LASTPIN (5025 1775) $PN 48
J 0
(5035 1785);
DISPLAY 0.680851 (5035 1785);
PAINT MONO (5035 1785);
FORCEPROP 0 LASTPIN (5025 1825) $PN 50
J 0
(5035 1835);
DISPLAY 0.680851 (5035 1835);
PAINT MONO (5035 1835);
FORCEPROP 0 LASTPIN (5025 1875) $PN 52
J 0
(5035 1885);
DISPLAY 0.680851 (5035 1885);
PAINT MONO (5035 1885);
FORCEPROP 0 LASTPIN (5025 1925) $PN 54
J 0
(5035 1935);
DISPLAY 0.680851 (5035 1935);
PAINT MONO (5035 1935);
FORCEPROP 0 LASTPIN (5025 1975) $PN 57
J 0
(5035 1985);
DISPLAY 0.680851 (5035 1985);
PAINT MONO (5035 1985);
FORCEPROP 0 LASTPIN (5025 2025) $PN 59
J 0
(5035 2035);
DISPLAY 0.680851 (5035 2035);
PAINT MONO (5035 2035);
FORCEPROP 0 LASTPIN (5025 2075) $PN 61
J 0
(5035 2085);
DISPLAY 0.680851 (5035 2085);
PAINT MONO (5035 2085);
FORCEPROP 0 LASTPIN (5025 2125) $PN 63
J 0
(5035 2135);
DISPLAY 0.680851 (5035 2135);
PAINT MONO (5035 2135);
FORCEPROP 0 LASTPIN (5025 2175) $PN 65
J 0
(5035 2185);
DISPLAY 0.680851 (5035 2185);
PAINT MONO (5035 2185);
FORCEPROP 0 LASTPIN (5025 2225) $PN 67
J 0
(5035 2235);
DISPLAY 0.680851 (5035 2235);
PAINT MONO (5035 2235);
FORCEPROP 0 LASTPIN (5025 2275) $PN 69
J 0
(5035 2285);
DISPLAY 0.680851 (5035 2285);
PAINT MONO (5035 2285);
FORCEPROP 0 LASTPIN (5025 2325) $PN 71
J 0
(5035 2335);
DISPLAY 0.680851 (5035 2335);
PAINT MONO (5035 2335);
FORCEPROP 0 LASTPIN (5025 2375) $PN 73
J 0
(5035 2385);
DISPLAY 0.680851 (5035 2385);
PAINT MONO (5035 2385);
FORCEPROP 0 LASTPIN (5025 2425) $PN 75
J 0
(5035 2435);
DISPLAY 0.680851 (5035 2435);
PAINT MONO (5035 2435);
FORCEPROP 0 LASTPIN (5025 2475) $PN 77
J 0
(5035 2485);
DISPLAY 0.680851 (5035 2485);
PAINT MONO (5035 2485);
FORCEPROP 0 LASTPIN (5025 2525) $PN 79
J 0
(5035 2535);
DISPLAY 0.680851 (5035 2535);
PAINT MONO (5035 2535);
FORCEPROP 0 LASTPIN (5025 2575) $PN 81
J 0
(5035 2585);
DISPLAY 0.680851 (5035 2585);
PAINT MONO (5035 2585);
FORCEPROP 0 LASTPIN (5025 2625) $PN 83
J 0
(5035 2635);
DISPLAY 0.680851 (5035 2635);
PAINT MONO (5035 2635);
FORCEPROP 0 LASTPIN (5025 2675) $PN 85
J 0
(5035 2685);
DISPLAY 0.680851 (5035 2685);
PAINT MONO (5035 2685);
FORCEPROP 0 LASTPIN (5025 2725) $PN 88
J 0
(5035 2735);
DISPLAY 0.680851 (5035 2735);
PAINT MONO (5035 2735);
FORCEPROP 0 LASTPIN (5025 2775) $PN 90
J 0
(5035 2785);
DISPLAY 0.680851 (5035 2785);
PAINT MONO (5035 2785);
FORCEPROP 0 LASTPIN (5025 2825) $PN 92
J 0
(5035 2835);
DISPLAY 0.680851 (5035 2835);
PAINT MONO (5035 2835);
FORCEPROP 0 LASTPIN (5025 2875) $PN 95
J 0
(5035 2885);
DISPLAY 0.680851 (5035 2885);
PAINT MONO (5035 2885);
FORCEPROP 0 LASTPIN (5025 2925) $PN 97
J 0
(5035 2935);
DISPLAY 0.680851 (5035 2935);
PAINT MONO (5035 2935);
FORCEPROP 0 LASTPIN (5025 2975) $PN 99
J 0
(5035 2985);
DISPLAY 0.680851 (5035 2985);
PAINT MONO (5035 2985);
FORCEPROP 0 LASTPIN (5025 3025) $PN 101
J 0
(5035 3035);
DISPLAY 0.680851 (5035 3035);
PAINT MONO (5035 3035);
FORCEPROP 0 LASTPIN (5025 3075) $PN 103
J 0
(5035 3085);
DISPLAY 0.680851 (5035 3085);
PAINT MONO (5035 3085);
FORCEPROP 0 LASTPIN (5025 3125) $PN 106
J 0
(5035 3135);
DISPLAY 0.680851 (5035 3135);
PAINT MONO (5035 3135);
FORCEPROP 0 LASTPIN (5025 3175) $PN 108
J 0
(5035 3185);
DISPLAY 0.680851 (5035 3185);
PAINT MONO (5035 3185);
FORCEPROP 0 LASTPIN (5025 3225) $PN 110
J 0
(5035 3235);
DISPLAY 0.680851 (5035 3235);
PAINT MONO (5035 3235);
FORCEPROP 0 LASTPIN (5025 3275) $PN 112
J 0
(5035 3285);
DISPLAY 0.680851 (5035 3285);
PAINT MONO (5035 3285);
FORCEPROP 0 LASTPIN (5025 3325) $PN 114
J 0
(5035 3335);
DISPLAY 0.680851 (5035 3335);
PAINT MONO (5035 3335);
FORCEPROP 0 LASTPIN (5025 3375) $PN 117
J 0
(5035 3385);
DISPLAY 0.680851 (5035 3385);
PAINT MONO (5035 3385);
FORCEPROP 0 LASTPIN (5025 3425) $PN 119
J 0
(5035 3435);
DISPLAY 0.680851 (5035 3435);
PAINT MONO (5035 3435);
FORCEPROP 0 LASTPIN (5025 3475) $PN 121
J 0
(5035 3485);
DISPLAY 0.680851 (5035 3485);
PAINT MONO (5035 3485);
FORCEPROP 0 LASTPIN (5025 3525) $PN 123
J 0
(5035 3535);
DISPLAY 0.680851 (5035 3535);
PAINT MONO (5035 3535);
FORCEPROP 0 LASTPIN (5025 3575) $PN 125
J 0
(5035 3585);
DISPLAY 0.680851 (5035 3585);
PAINT MONO (5035 3585);
FORCEPROP 0 LASTPIN (5025 3625) $PN 128
J 0
(5035 3635);
DISPLAY 0.680851 (5035 3635);
PAINT MONO (5035 3635);
FORCEPROP 0 LASTPIN (5025 3675) $PN 130
J 0
(5035 3685);
DISPLAY 0.680851 (5035 3685);
PAINT MONO (5035 3685);
FORCEPROP 0 LASTPIN (5025 3725) $PN 132
J 0
(5035 3735);
DISPLAY 0.680851 (5035 3735);
PAINT MONO (5035 3735);
FORCEPROP 0 LASTPIN (5025 3775) $PN 134
J 0
(5035 3785);
DISPLAY 0.680851 (5035 3785);
PAINT MONO (5035 3785);
FORCEPROP 0 LASTPIN (5025 3825) $PN 136
J 0
(5035 3835);
DISPLAY 0.680851 (5035 3835);
PAINT MONO (5035 3835);
FORCEPROP 0 LASTPIN (5025 3875) $PN 139
J 0
(5035 3885);
DISPLAY 0.680851 (5035 3885);
PAINT MONO (5035 3885);
FORCEPROP 0 LASTPIN (5025 3925) $PN 141
J 0
(5035 3935);
DISPLAY 0.680851 (5035 3935);
PAINT MONO (5035 3935);
FORCEPROP 0 LASTPIN (5025 3975) $PN 143
J 0
(5035 3985);
DISPLAY 0.680851 (5035 3985);
PAINT MONO (5035 3985);
FORCEPROP 0 LASTPIN (3825 725) $PN 151
J 2
(3815 735);
DISPLAY 0.680851 (3815 735);
PAINT MONO (3815 735);
FORCEPROP 0 LASTPIN (3825 775) $PN 153
J 2
(3815 785);
DISPLAY 0.680851 (3815 785);
PAINT MONO (3815 785);
FORCEPROP 0 LASTPIN (3825 825) $PN 155
J 2
(3815 835);
DISPLAY 0.680851 (3815 835);
PAINT MONO (3815 835);
FORCEPROP 0 LASTPIN (3825 875) $PN 158
J 2
(3815 885);
DISPLAY 0.680851 (3815 885);
PAINT MONO (3815 885);
FORCEPROP 0 LASTPIN (3825 925) $PN 160
J 2
(3815 935);
DISPLAY 0.680851 (3815 935);
PAINT MONO (3815 935);
FORCEPROP 0 LASTPIN (3825 975) $PN 162
J 2
(3815 985);
DISPLAY 0.680851 (3815 985);
PAINT MONO (3815 985);
FORCEPROP 0 LASTPIN (3825 1025) $PN 164
J 2
(3815 1035);
DISPLAY 0.680851 (3815 1035);
PAINT MONO (3815 1035);
FORCEPROP 0 LASTPIN (3825 1075) $PN 166
J 2
(3815 1085);
DISPLAY 0.680851 (3815 1085);
PAINT MONO (3815 1085);
FORCEPROP 0 LASTPIN (3825 1125) $PN 169
J 2
(3815 1135);
DISPLAY 0.680851 (3815 1135);
PAINT MONO (3815 1135);
FORCEPROP 0 LASTPIN (3825 1175) $PN 171
J 2
(3815 1185);
DISPLAY 0.680851 (3815 1185);
PAINT MONO (3815 1185);
FORCEPROP 0 LASTPIN (3825 1225) $PN 173
J 2
(3815 1235);
DISPLAY 0.680851 (3815 1235);
PAINT MONO (3815 1235);
FORCEPROP 0 LASTPIN (3825 1275) $PN 175
J 2
(3815 1285);
DISPLAY 0.680851 (3815 1285);
PAINT MONO (3815 1285);
FORCEPROP 0 LASTPIN (3825 1325) $PN 177
J 2
(3815 1335);
DISPLAY 0.680851 (3815 1335);
PAINT MONO (3815 1335);
FORCEPROP 0 LASTPIN (3825 1375) $PN 180
J 2
(3815 1385);
DISPLAY 0.680851 (3815 1385);
PAINT MONO (3815 1385);
FORCEPROP 0 LASTPIN (3825 1425) $PN 182
J 2
(3815 1435);
DISPLAY 0.680851 (3815 1435);
PAINT MONO (3815 1435);
FORCEPROP 0 LASTPIN (3825 1475) $PN 184
J 2
(3815 1485);
DISPLAY 0.680851 (3815 1485);
PAINT MONO (3815 1485);
FORCEPROP 0 LASTPIN (3825 1525) $PN 186
J 2
(3815 1535);
DISPLAY 0.680851 (3815 1535);
PAINT MONO (3815 1535);
FORCEPROP 0 LASTPIN (3825 1575) $PN 188
J 2
(3815 1585);
DISPLAY 0.680851 (3815 1585);
PAINT MONO (3815 1585);
FORCEPROP 0 LASTPIN (3825 1625) $PN 191
J 2
(3815 1635);
DISPLAY 0.680851 (3815 1635);
PAINT MONO (3815 1635);
FORCEPROP 0 LASTPIN (3825 1675) $PN 193
J 2
(3815 1685);
DISPLAY 0.680851 (3815 1685);
PAINT MONO (3815 1685);
FORCEPROP 0 LASTPIN (3825 1725) $PN 195
J 2
(3815 1735);
DISPLAY 0.680851 (3815 1735);
PAINT MONO (3815 1735);
FORCEPROP 0 LASTPIN (3825 1775) $PN 197
J 2
(3815 1785);
DISPLAY 0.680851 (3815 1785);
PAINT MONO (3815 1785);
FORCEPROP 0 LASTPIN (3825 1825) $PN 199
J 2
(3815 1835);
DISPLAY 0.680851 (3815 1835);
PAINT MONO (3815 1835);
FORCEPROP 0 LASTPIN (3825 1875) $PN 202
J 2
(3815 1885);
DISPLAY 0.680851 (3815 1885);
PAINT MONO (3815 1885);
FORCEPROP 0 LASTPIN (3825 1925) $PN 204
J 2
(3815 1935);
DISPLAY 0.680851 (3815 1935);
PAINT MONO (3815 1935);
FORCEPROP 0 LASTPIN (3825 1975) $PN 206
J 2
(3815 1985);
DISPLAY 0.680851 (3815 1985);
PAINT MONO (3815 1985);
FORCEPROP 0 LASTPIN (3825 2025) $PN 208
J 2
(3815 2035);
DISPLAY 0.680851 (3815 2035);
PAINT MONO (3815 2035);
FORCEPROP 0 LASTPIN (3825 2075) $PN 210
J 2
(3815 2085);
DISPLAY 0.680851 (3815 2085);
PAINT MONO (3815 2085);
FORCEPROP 0 LASTPIN (3825 2125) $PN 212
J 2
(3815 2135);
DISPLAY 0.680851 (3815 2135);
PAINT MONO (3815 2135);
FORCEPROP 0 LASTPIN (3825 2175) $PN 214
J 2
(3815 2185);
DISPLAY 0.680851 (3815 2185);
PAINT MONO (3815 2185);
FORCEPROP 0 LASTPIN (3825 2225) $PN 216
J 2
(3815 2235);
DISPLAY 0.680851 (3815 2235);
PAINT MONO (3815 2235);
FORCEPROP 0 LASTPIN (3825 2275) $PN 219
J 2
(3815 2285);
DISPLAY 0.680851 (3815 2285);
PAINT MONO (3815 2285);
FORCEPROP 0 LASTPIN (3825 2325) $PN 222
J 2
(3815 2335);
DISPLAY 0.680851 (3815 2335);
PAINT MONO (3815 2335);
FORCEPROP 0 LASTPIN (3825 2375) $PN 224
J 2
(3815 2385);
DISPLAY 0.680851 (3815 2385);
PAINT MONO (3815 2385);
FORCEPROP 0 LASTPIN (3825 2425) $PN 226
J 2
(3815 2435);
DISPLAY 0.680851 (3815 2435);
PAINT MONO (3815 2435);
FORCEPROP 0 LASTPIN (3825 2475) $PN 228
J 2
(3815 2485);
DISPLAY 0.680851 (3815 2485);
PAINT MONO (3815 2485);
FORCEPROP 0 LASTPIN (3825 2525) $PN 230
J 2
(3815 2535);
DISPLAY 0.680851 (3815 2535);
PAINT MONO (3815 2535);
FORCEPROP 0 LASTPIN (3825 2575) $PN 233
J 2
(3815 2585);
DISPLAY 0.680851 (3815 2585);
PAINT MONO (3815 2585);
FORCEPROP 0 LASTPIN (3825 2625) $PN 235
J 2
(3815 2635);
DISPLAY 0.680851 (3815 2635);
PAINT MONO (3815 2635);
FORCEPROP 0 LASTPIN (3825 2675) $PN 237
J 2
(3815 2685);
DISPLAY 0.680851 (3815 2685);
PAINT MONO (3815 2685);
FORCEPROP 0 LASTPIN (3825 2725) $PN 240
J 2
(3815 2735);
DISPLAY 0.680851 (3815 2735);
PAINT MONO (3815 2735);
FORCEPROP 0 LASTPIN (3825 2775) $PN 242
J 2
(3815 2785);
DISPLAY 0.680851 (3815 2785);
PAINT MONO (3815 2785);
FORCEPROP 0 LASTPIN (3825 2825) $PN 244
J 2
(3815 2835);
DISPLAY 0.680851 (3815 2835);
PAINT MONO (3815 2835);
FORCEPROP 0 LASTPIN (3825 2875) $PN 246
J 2
(3815 2885);
DISPLAY 0.680851 (3815 2885);
PAINT MONO (3815 2885);
FORCEPROP 0 LASTPIN (3825 2925) $PN 248
J 2
(3815 2935);
DISPLAY 0.680851 (3815 2935);
PAINT MONO (3815 2935);
FORCEPROP 0 LASTPIN (3825 2975) $PN 251
J 2
(3815 2985);
DISPLAY 0.680851 (3815 2985);
PAINT MONO (3815 2985);
FORCEPROP 0 LASTPIN (3825 3025) $PN 253
J 2
(3815 3035);
DISPLAY 0.680851 (3815 3035);
PAINT MONO (3815 3035);
FORCEPROP 0 LASTPIN (3825 3075) $PN 255
J 2
(3815 3085);
DISPLAY 0.680851 (3815 3085);
PAINT MONO (3815 3085);
FORCEPROP 0 LASTPIN (3825 3125) $PN 257
J 2
(3815 3135);
DISPLAY 0.680851 (3815 3135);
PAINT MONO (3815 3135);
FORCEPROP 0 LASTPIN (3825 3175) $PN 259
J 2
(3815 3185);
DISPLAY 0.680851 (3815 3185);
PAINT MONO (3815 3185);
FORCEPROP 0 LASTPIN (3825 3225) $PN 262
J 2
(3815 3235);
DISPLAY 0.680851 (3815 3235);
PAINT MONO (3815 3235);
FORCEPROP 0 LASTPIN (3825 3275) $PN 264
J 2
(3815 3285);
DISPLAY 0.680851 (3815 3285);
PAINT MONO (3815 3285);
FORCEPROP 0 LASTPIN (3825 3325) $PN 266
J 2
(3815 3335);
DISPLAY 0.680851 (3815 3335);
PAINT MONO (3815 3335);
FORCEPROP 0 LASTPIN (3825 3375) $PN 268
J 2
(3815 3385);
DISPLAY 0.680851 (3815 3385);
PAINT MONO (3815 3385);
FORCEPROP 0 LASTPIN (3825 3425) $PN 270
J 2
(3815 3435);
DISPLAY 0.680851 (3815 3435);
PAINT MONO (3815 3435);
FORCEPROP 0 LASTPIN (3825 3475) $PN 273
J 2
(3815 3485);
DISPLAY 0.680851 (3815 3485);
PAINT MONO (3815 3485);
FORCEPROP 0 LASTPIN (3825 3525) $PN 275
J 2
(3815 3535);
DISPLAY 0.680851 (3815 3535);
PAINT MONO (3815 3535);
FORCEPROP 0 LASTPIN (3825 3575) $PN 277
J 2
(3815 3585);
DISPLAY 0.680851 (3815 3585);
PAINT MONO (3815 3585);
FORCEPROP 0 LASTPIN (3825 3625) $PN 279
J 2
(3815 3635);
DISPLAY 0.680851 (3815 3635);
PAINT MONO (3815 3635);
FORCEPROP 0 LASTPIN (3825 3675) $PN 281
J 2
(3815 3685);
DISPLAY 0.680851 (3815 3685);
PAINT MONO (3815 3685);
FORCEPROP 0 LASTPIN (3825 3725) $PN 284
J 2
(3815 3735);
DISPLAY 0.680851 (3815 3735);
PAINT MONO (3815 3735);
FORCEPROP 0 LASTPIN (3825 3775) $PN 286
J 2
(3815 3785);
DISPLAY 0.680851 (3815 3785);
PAINT MONO (3815 3785);
FORCEPROP 0 LASTPIN (3825 3825) $PN 288
J 2
(3815 3835);
DISPLAY 0.680851 (3815 3835);
PAINT MONO (3815 3835);
FORCEPROP 1 LAST NEEDS_NO_SIZE TRUE
J 0
(4425 2350);
DISPLAY 0.723404 (4425 2350);
PAINT GREEN (4425 2350);
DISPLAY INVISIBLE (4425 2350);
FORCEPROP 1 LAST CDS_LMAN_SYM_OUTLINE -450,1775,450,-1775
J 0
(4425 2350);
DISPLAY 0.468085 (4425 2350);
PAINT GREEN (4425 2350);
DISPLAY INVISIBLE (4425 2350);
FORCEPROP 2 LAST CDS_LIB pure_quanta
J 0
(4425 2350);
DISPLAY INVISIBLE (4425 2350);
FORCEPROP 2 LAST CDS_LOCATION J15
J 0
(3975 4475);
DISPLAY 1.021277 (3975 4475);
DISPLAY INVISIBLE (3975 4475);
FORCEPROP 0 LAST $SEC 3
J 0
(3975 4475);
DISPLAY 0.680851 (3975 4475);
PAINT MONO (3975 4475);
DISPLAY INVISIBLE (3975 4475);
FORCEPROP 2 LAST CDS_SEC 3
J 0
(3975 4475);
DISPLAY 1.021277 (3975 4475);
DISPLAY INVISIBLE (3975 4475);
FORCEPROP 1 LAST PATH I176
J 0
(4425 2350);
DISPLAY 0.723404 (4425 2350);
PAINT GREEN (4425 2350);
DISPLAY INVISIBLE (4425 2350);
FORCEADD UNIVERSAL_GND..1
(5275 275);
FORCEPROP 3 LASTPIN (5275 325) SIG_NAME GND\g
J 0
(5285 335);
DISPLAY 0.659574 (5285 335);
PAINT MONO (5285 335);
DISPLAY INVISIBLE (5285 335);
FORCEPROP 2 LAST CDS_LIB logical_power
J 0
(5275 275);
PAINT MONO (5275 275);
DISPLAY INVISIBLE (5275 275);
FORCEPROP 1 LAST HDL_POWER GND
J 1
(5300 200);
DISPLAY 0.872340 (5300 200);
PAINT GREEN (5300 200);
DISPLAY INVISIBLE (5300 200);
FORCEPROP 1 LAST PATH I177
J 0
(5350 275);
DISPLAY 0.872340 (5350 275);
PAINT AQUA (5350 275);
DISPLAY INVISIBLE (5350 275);
FORCEADD SCONN288_ADR50017P130CC..2
(1000 2975);
FORCEPROP 1 LAST PART_NUMBER DFHST8FS461
J 0
(407 4275);
DISPLAY 0.723404 (407 4275);
PAINT GREEN (407 4275);
DISPLAY INVISIBLE (407 4275);
FORCEPROP 2 LAST PART_TYPE SMLF
J 0
(418 4428);
DISPLAY 1.021277 (418 4428);
FORCEPROP 2 LAST VALUE SCONN288_ADR50017-P130CC
J 0
(418 4378);
DISPLAY 1.021277 (418 4378);
FORCEPROP 1 LAST MATERIAL IO
J 0
(407 4148);
DISPLAY 0.723404 (407 4148);
PAINT GREEN (407 4148);
FORCEPROP 1 LAST LOCATION J15
J 0
(400 4325);
DISPLAY 0.723404 (400 4325);
PAINT GREEN (400 4325);
FORCEPROP 0 LASTPIN (1750 3025) $PN 12
J 0
(1760 3035);
DISPLAY 0.680851 (1760 3035);
PAINT MONO (1760 3035);
FORCEPROP 0 LASTPIN (1750 3075) $PN 11
J 0
(1760 3085);
DISPLAY 0.680851 (1760 3085);
PAINT MONO (1760 3085);
FORCEPROP 0 LASTPIN (1750 1975) $PN 105
J 0
(1760 1985);
DISPLAY 0.680851 (1760 1985);
PAINT MONO (1760 1985);
FORCEPROP 0 LASTPIN (1750 2025) $PN 104
J 0
(1760 2035);
DISPLAY 0.680851 (1760 2035);
PAINT MONO (1760 2035);
FORCEPROP 0 LASTPIN (1750 3125) $PN 23
J 0
(1760 3135);
DISPLAY 0.680851 (1760 3135);
PAINT MONO (1760 3135);
FORCEPROP 0 LASTPIN (1750 3175) $PN 22
J 0
(1760 3185);
DISPLAY 0.680851 (1760 3185);
PAINT MONO (1760 3185);
FORCEPROP 0 LASTPIN (1750 2075) $PN 116
J 0
(1760 2085);
DISPLAY 0.680851 (1760 2085);
PAINT MONO (1760 2085);
FORCEPROP 0 LASTPIN (1750 2125) $PN 115
J 0
(1760 2135);
DISPLAY 0.680851 (1760 2135);
PAINT MONO (1760 2135);
FORCEPROP 0 LASTPIN (1750 3225) $PN 34
J 0
(1760 3235);
DISPLAY 0.680851 (1760 3235);
PAINT MONO (1760 3235);
FORCEPROP 0 LASTPIN (1750 3275) $PN 33
J 0
(1760 3285);
DISPLAY 0.680851 (1760 3285);
PAINT MONO (1760 3285);
FORCEPROP 0 LASTPIN (1750 2175) $PN 127
J 0
(1760 2185);
DISPLAY 0.680851 (1760 2185);
PAINT MONO (1760 2185);
FORCEPROP 0 LASTPIN (1750 2225) $PN 126
J 0
(1760 2235);
DISPLAY 0.680851 (1760 2235);
PAINT MONO (1760 2235);
FORCEPROP 0 LASTPIN (1750 3325) $PN 45
J 0
(1760 3335);
DISPLAY 0.680851 (1760 3335);
PAINT MONO (1760 3335);
FORCEPROP 0 LASTPIN (1750 3375) $PN 44
J 0
(1760 3385);
DISPLAY 0.680851 (1760 3385);
PAINT MONO (1760 3385);
FORCEPROP 0 LASTPIN (1750 2275) $PN 138
J 0
(1760 2285);
DISPLAY 0.680851 (1760 2285);
PAINT MONO (1760 2285);
FORCEPROP 0 LASTPIN (1750 2325) $PN 137
J 0
(1760 2335);
DISPLAY 0.680851 (1760 2335);
PAINT MONO (1760 2335);
FORCEPROP 0 LASTPIN (1750 3425) $PN 56
J 0
(1760 3435);
DISPLAY 0.680851 (1760 3435);
PAINT MONO (1760 3435);
FORCEPROP 0 LASTPIN (1750 3475) $PN 55
J 0
(1760 3485);
DISPLAY 0.680851 (1760 3485);
PAINT MONO (1760 3485);
FORCEPROP 0 LASTPIN (1750 2375) $PN 238
J 0
(1760 2385);
DISPLAY 0.680851 (1760 2385);
PAINT MONO (1760 2385);
FORCEPROP 0 LASTPIN (1750 2425) $PN 239
J 0
(1760 2435);
DISPLAY 0.680851 (1760 2435);
PAINT MONO (1760 2435);
FORCEPROP 0 LASTPIN (1750 3525) $PN 156
J 0
(1760 3535);
DISPLAY 0.680851 (1760 3535);
PAINT MONO (1760 3535);
FORCEPROP 0 LASTPIN (1750 3575) $PN 157
J 0
(1760 3585);
DISPLAY 0.680851 (1760 3585);
PAINT MONO (1760 3585);
FORCEPROP 0 LASTPIN (1750 2475) $PN 249
J 0
(1760 2485);
DISPLAY 0.680851 (1760 2485);
PAINT MONO (1760 2485);
FORCEPROP 0 LASTPIN (1750 2525) $PN 250
J 0
(1760 2535);
DISPLAY 0.680851 (1760 2535);
PAINT MONO (1760 2535);
FORCEPROP 0 LASTPIN (1750 3625) $PN 167
J 0
(1760 3635);
DISPLAY 0.680851 (1760 3635);
PAINT MONO (1760 3635);
FORCEPROP 0 LASTPIN (1750 3675) $PN 168
J 0
(1760 3685);
DISPLAY 0.680851 (1760 3685);
PAINT MONO (1760 3685);
FORCEPROP 0 LASTPIN (1750 2575) $PN 260
J 0
(1760 2585);
DISPLAY 0.680851 (1760 2585);
PAINT MONO (1760 2585);
FORCEPROP 0 LASTPIN (1750 2625) $PN 261
J 0
(1760 2635);
DISPLAY 0.680851 (1760 2635);
PAINT MONO (1760 2635);
FORCEPROP 0 LASTPIN (1750 3725) $PN 178
J 0
(1760 3735);
DISPLAY 0.680851 (1760 3735);
PAINT MONO (1760 3735);
FORCEPROP 0 LASTPIN (1750 3775) $PN 179
J 0
(1760 3785);
DISPLAY 0.680851 (1760 3785);
PAINT MONO (1760 3785);
FORCEPROP 0 LASTPIN (1750 2675) $PN 271
J 0
(1760 2685);
DISPLAY 0.680851 (1760 2685);
PAINT MONO (1760 2685);
FORCEPROP 0 LASTPIN (1750 2725) $PN 272
J 0
(1760 2735);
DISPLAY 0.680851 (1760 2735);
PAINT MONO (1760 2735);
FORCEPROP 0 LASTPIN (1750 3825) $PN 189
J 0
(1760 3835);
DISPLAY 0.680851 (1760 3835);
PAINT MONO (1760 3835);
FORCEPROP 0 LASTPIN (1750 3875) $PN 190
J 0
(1760 3885);
DISPLAY 0.680851 (1760 3885);
PAINT MONO (1760 3885);
FORCEPROP 0 LASTPIN (1750 2775) $PN 282
J 0
(1760 2785);
DISPLAY 0.680851 (1760 2785);
PAINT MONO (1760 2785);
FORCEPROP 0 LASTPIN (1750 2825) $PN 283
J 0
(1760 2835);
DISPLAY 0.680851 (1760 2835);
PAINT MONO (1760 2835);
FORCEPROP 0 LASTPIN (1750 3925) $PN 200
J 0
(1760 3935);
DISPLAY 0.680851 (1760 3935);
PAINT MONO (1760 3935);
FORCEPROP 0 LASTPIN (1750 3975) $PN 201
J 0
(1760 3985);
DISPLAY 0.680851 (1760 3985);
PAINT MONO (1760 3985);
FORCEPROP 0 LASTPIN (1750 2875) $PN 94
J 0
(1760 2885);
DISPLAY 0.680851 (1760 2885);
PAINT MONO (1760 2885);
FORCEPROP 0 LASTPIN (1750 2925) $PN 93
J 0
(1760 2935);
DISPLAY 0.680851 (1760 2935);
PAINT MONO (1760 2935);
FORCEPROP 1 LAST NEEDS_NO_SIZE TRUE
J 0
(1000 2975);
DISPLAY 0.723404 (1000 2975);
PAINT GREEN (1000 2975);
DISPLAY INVISIBLE (1000 2975);
FORCEPROP 1 LAST CDS_LMAN_SYM_OUTLINE -600,1150,600,-1150
J 0
(1000 2975);
DISPLAY 0.468085 (1000 2975);
PAINT GREEN (1000 2975);
DISPLAY INVISIBLE (1000 2975);
FORCEPROP 2 LAST CDS_LIB pure_quanta
J 0
(1000 2975);
DISPLAY INVISIBLE (1000 2975);
FORCEPROP 0 LAST $SEC 2
J 0
(425 4500);
DISPLAY 0.680851 (425 4500);
PAINT MONO (425 4500);
DISPLAY INVISIBLE (425 4500);
FORCEPROP 0 LAST CDS_SEC 2
J 0
(425 4500);
DISPLAY 1.021277 (425 4500);
DISPLAY INVISIBLE (425 4500);
FORCEPROP 1 LAST PATH I178
J 0
(1000 2975);
DISPLAY 0.723404 (1000 2975);
PAINT GREEN (1000 2975);
DISPLAY INVISIBLE (1000 2975);
FORCEADD Q_RES..1
(-3450 1250);
FORCEPROP 1 LAST PART_NUMBER CS04992FB07
J 0
(-3350 1225);
DISPLAY 0.404255 (-3350 1225);
DISPLAY INVISIBLE (-3350 1225);
FORCEPROP 1 LAST VALUE 49.9
J 2
(-3225 1250);
DISPLAY 0.510638 (-3225 1250);
FORCEPROP 1 LAST MATERIAL CHIP
J 0
(-3650 1225);
DISPLAY 0.404255 (-3650 1225);
FORCEPROP 1 LAST $LOCATION R3889
J 0
(-3675 1250);
DISPLAY 0.638298 (-3675 1250);
FORCEPROP 1 LASTPIN (-3550 1250) $PN 1
J 0
(-3538 1262);
DISPLAY 0.787234 (-3538 1262);
PAINT MONO (-3538 1262);
FORCEPROP 1 LASTPIN (-3350 1250) $PN 2
J 0
(-3388 1262);
DISPLAY 0.787234 (-3388 1262);
PAINT MONO (-3388 1262);
FORCEPROP 2 LAST CDS_LIB pure_quanta
J 0
(-3450 1250);
DISPLAY INVISIBLE (-3450 1250);
FORCEPROP 1 LAST PACK_TYPE 0402LF
J 0
(-3150 1250);
DISPLAY 0.510638 (-3150 1250);
DISPLAY INVISIBLE (-3150 1250);
FORCEPROP 1 LAST WATTAGE 1/16W
J 2
(-3150 1200);
DISPLAY 0.404255 (-3150 1200);
DISPLAY INVISIBLE (-3150 1200);
FORCEPROP 1 LAST TOLERANCE 1%
J 0
(-3225 1250);
DISPLAY 0.510638 (-3225 1250);
DISPLAY INVISIBLE (-3225 1250);
FORCEPROP 0 LAST CDS_LOCATION R3889
J 0
(-3600 1300);
DISPLAY 1.021277 (-3600 1300);
DISPLAY INVISIBLE (-3600 1300);
FORCEPROP 0 LAST $SEC 1
J 0
(-3600 1300);
DISPLAY 0.680851 (-3600 1300);
PAINT MONO (-3600 1300);
DISPLAY INVISIBLE (-3600 1300);
FORCEPROP 0 LAST CDS_SEC 1
J 0
(-3600 1300);
DISPLAY 1.021277 (-3600 1300);
DISPLAY INVISIBLE (-3600 1300);
FORCEPROP 1 LAST PATH I179
J 0
(-3500 1400);
DISPLAY 0.978723 (-3500 1400);
PAINT WHITE (-3500 1400);
DISPLAY INVISIBLE (-3500 1400);
FORCEADD OFFPAGE..1
(-3425 3175);
FORCEPROP 2 LAST $XR1 97 
J 0
(-3736 3175);
DISPLAY 0.638298 (-3736 3175);
PAINT MONO (-3736 3175);
FORCEPROP 2 LAST $XR0 27 
J 0
(-3646 3175);
DISPLAY 0.638298 (-3646 3175);
PAINT MONO (-3646 3175);
FORCEPROP 2 LAST CDS_LIB standard
J 0
(-3425 3175);
PAINT MONO (-3425 3175);
DISPLAY INVISIBLE (-3425 3175);
FORCEPROP 1 LAST OFFPAGE TRUE
J 0
(-3100 3050);
DISPLAY 0.872340 (-3100 3050);
DISPLAY INVISIBLE (-3100 3050);
FORCEPROP 1 LAST COMMENT_BODY TRUE
J 0
(-3300 3075);
DISPLAY 0.872340 (-3300 3075);
PAINT GREEN (-3300 3075);
DISPLAY INVISIBLE (-3300 3075);
FORCEPROP 2 LAST PATH I18
J 0
(-3375 3250);
DISPLAY 1.021277 (-3375 3250);
DISPLAY INVISIBLE (-3375 3250);
FORCEADD OFFPAGE..1
(-2275 1200);
FORCEPROP 2 LAST $XR7 97 
J 0
(-3157 1200);
DISPLAY 0.638298 (-3157 1200);
PAINT MONO (-3157 1200);
FORCEPROP 2 LAST $XR6 95 
J 0
(-3067 1200);
DISPLAY 0.638298 (-3067 1200);
PAINT MONO (-3067 1200);
FORCEPROP 2 LAST $XR5 94 
J 0
(-2977 1200);
DISPLAY 0.638298 (-2977 1200);
PAINT MONO (-2977 1200);
FORCEPROP 2 LAST $XR4 93 
J 0
(-2887 1200);
DISPLAY 0.638298 (-2887 1200);
PAINT MONO (-2887 1200);
FORCEPROP 2 LAST $XR3 92 
J 0
(-2797 1200);
DISPLAY 0.638298 (-2797 1200);
PAINT MONO (-2797 1200);
FORCEPROP 2 LAST $XR2 91 
J 0
(-2707 1200);
DISPLAY 0.638298 (-2707 1200);
PAINT MONO (-2707 1200);
FORCEPROP 2 LAST $XR1 90 
J 0
(-2617 1200);
DISPLAY 0.638298 (-2617 1200);
PAINT MONO (-2617 1200);
FORCEPROP 2 LAST $XR0 229 
J 0
(-2527 1200);
DISPLAY 0.638298 (-2527 1200);
PAINT MONO (-2527 1200);
FORCEPROP 2 LAST CDS_LIB standard
J 2
(-2275 1200);
DISPLAY INVISIBLE (-2275 1200);
FORCEPROP 1 LAST OFFPAGE TRUE
J 0
(-1950 1075);
DISPLAY 0.872340 (-1950 1075);
DISPLAY INVISIBLE (-1950 1075);
FORCEPROP 1 LAST COMMENT_BODY TRUE
J 0
(-2150 1100);
DISPLAY 0.872340 (-2150 1100);
PAINT GREEN (-2150 1100);
DISPLAY INVISIBLE (-2150 1100);
FORCEPROP 2 LAST PATH I180
J 2
(-2450 1275);
DISPLAY 1.021277 (-2450 1275);
DISPLAY INVISIBLE (-2450 1275);
FORCEADD OFFPAGE..1
(-3425 3025);
FORCEPROP 2 LAST $XR0 27 
J 0
(-3646 3025);
DISPLAY 0.638298 (-3646 3025);
PAINT MONO (-3646 3025);
FORCEPROP 2 LAST CDS_LIB standard
J 0
(-3425 3025);
PAINT MONO (-3425 3025);
DISPLAY INVISIBLE (-3425 3025);
FORCEPROP 1 LAST OFFPAGE TRUE
J 0
(-3100 2900);
DISPLAY 0.872340 (-3100 2900);
DISPLAY INVISIBLE (-3100 2900);
FORCEPROP 1 LAST COMMENT_BODY TRUE
J 0
(-3300 2925);
DISPLAY 0.872340 (-3300 2925);
PAINT GREEN (-3300 2925);
DISPLAY INVISIBLE (-3300 2925);
FORCEPROP 2 LAST PATH I19
J 0
(-3375 3100);
DISPLAY 1.021277 (-3375 3100);
DISPLAY INVISIBLE (-3375 3100);
FORCEADD OFFPAGE..2
R 2
(-3425 25);
FORCEPROP 2 LAST $XR0 96 
J 0
(-3649 25);
DISPLAY 0.638298 (-3649 25);
PAINT MONO (-3649 25);
FORCEPROP 2 LAST CDS_LIB standard
J 0
(-3425 25);
PAINT MONO (-3425 25);
DISPLAY INVISIBLE (-3425 25);
FORCEPROP 1 LAST OFFPAGE TRUE
J 2
(-3750 -100);
DISPLAY 0.872340 (-3750 -100);
DISPLAY INVISIBLE (-3750 -100);
FORCEPROP 1 LAST COMMENT_BODY TRUE
J 2
(-3380 -70);
DISPLAY 0.872340 (-3380 -70);
PAINT GREEN (-3380 -70);
DISPLAY INVISIBLE (-3380 -70);
FORCEPROP 2 LAST PATH I2
J 0
(-3375 100);
DISPLAY 1.021277 (-3375 100);
DISPLAY INVISIBLE (-3375 100);
FORCEADD OFFPAGE..1
(-3425 3125);
FORCEPROP 2 LAST $XR1 97 
J 0
(-3736 3125);
DISPLAY 0.638298 (-3736 3125);
PAINT MONO (-3736 3125);
FORCEPROP 2 LAST $XR0 27 
J 0
(-3646 3125);
DISPLAY 0.638298 (-3646 3125);
PAINT MONO (-3646 3125);
FORCEPROP 2 LAST CDS_LIB standard
J 0
(-3425 3125);
PAINT MONO (-3425 3125);
DISPLAY INVISIBLE (-3425 3125);
FORCEPROP 1 LAST OFFPAGE TRUE
J 0
(-3100 3000);
DISPLAY 0.872340 (-3100 3000);
DISPLAY INVISIBLE (-3100 3000);
FORCEPROP 1 LAST COMMENT_BODY TRUE
J 0
(-3300 3025);
DISPLAY 0.872340 (-3300 3025);
PAINT GREEN (-3300 3025);
DISPLAY INVISIBLE (-3300 3025);
FORCEPROP 2 LAST PATH I20
J 0
(-3375 3200);
DISPLAY 1.021277 (-3375 3200);
DISPLAY INVISIBLE (-3375 3200);
FORCEADD OFFPAGE..1
(-3425 3600);
FORCEPROP 2 LAST $XR1 97 
J 0
(-3736 3600);
DISPLAY 0.638298 (-3736 3600);
PAINT MONO (-3736 3600);
FORCEPROP 2 LAST $XR0 27 
J 0
(-3646 3600);
DISPLAY 0.638298 (-3646 3600);
PAINT MONO (-3646 3600);
FORCEPROP 2 LAST CDS_LIB standard
J 0
(-3425 3600);
PAINT MONO (-3425 3600);
DISPLAY INVISIBLE (-3425 3600);
FORCEPROP 1 LAST OFFPAGE TRUE
J 0
(-3100 3475);
DISPLAY 0.872340 (-3100 3475);
DISPLAY INVISIBLE (-3100 3475);
FORCEPROP 1 LAST COMMENT_BODY TRUE
J 0
(-3300 3500);
DISPLAY 0.872340 (-3300 3500);
PAINT GREEN (-3300 3500);
DISPLAY INVISIBLE (-3300 3500);
FORCEPROP 2 LAST PATH I21
J 0
(-3375 3675);
DISPLAY 1.021277 (-3375 3675);
DISPLAY INVISIBLE (-3375 3675);
FORCEADD VCC_CORE..1
(-3325 1850);
FORCEPROP 3 LASTPIN (-3325 1800) SIG_NAME P3V3_AUX\g
J 0
(-3315 1810);
DISPLAY 0.659574 (-3315 1810);
PAINT MONO (-3315 1810);
DISPLAY INVISIBLE (-3315 1810);
FORCEPROP 1 LAST HDL_POWER P3V3_AUX
J 1
(-3325 1900);
DISPLAY 1.148936 (-3325 1900);
PAINT GREEN (-3325 1900);
FORCEPROP 2 LAST CDS_LIB logical_power
J 0
(-3325 1850);
PAINT MONO (-3325 1850);
DISPLAY INVISIBLE (-3325 1850);
FORCEPROP 1 LAST PATH I22
J 0
(-3275 1875);
DISPLAY 0.872340 (-3275 1875);
PAINT AQUA (-3275 1875);
DISPLAY INVISIBLE (-3275 1875);
FORCEADD TAP..1
R 2
(-2500 1775);
FORCEPROP 3 LASTPIN (-2450 1775) SIG_NAME M_H_CPU0_SB_CB<0>
J 0
(-2440 1785);
DISPLAY 0.659574 (-2440 1785);
PAINT MONO (-2440 1785);
DISPLAY INVISIBLE (-2440 1785);
FORCEPROP 1 LASTPIN (-2450 1775) BN 0
J 2
(-2438 1783);
DISPLAY 0.680851 (-2438 1783);
PAINT GREEN (-2438 1783);
FORCEPROP 2 LAST CDS_LIB standard
J 0
(-2500 1775);
PAINT MONO (-2500 1775);
DISPLAY INVISIBLE (-2500 1775);
FORCEPROP 1 LAST BODY_TYPE PLUMBING
J 2
(-2500 1825);
DISPLAY 0.872340 (-2500 1825);
PAINT GREEN (-2500 1825);
DISPLAY INVISIBLE (-2500 1825);
FORCEPROP 1 LAST HDL_TAP TRUE
J 2
(-2825 1650);
DISPLAY 0.872340 (-2825 1650);
DISPLAY INVISIBLE (-2825 1650);
FORCEPROP 1 LAST PATH I23
J 2
(-2498 1775);
DISPLAY 0.872340 (-2498 1775);
PAINT GREEN (-2498 1775);
DISPLAY INVISIBLE (-2498 1775);
FORCEADD TAP..1
R 2
(-2500 1875);
FORCEPROP 3 LASTPIN (-2450 1875) SIG_NAME M_H_CPU0_SB_CB<2>
J 0
(-2440 1885);
DISPLAY 0.659574 (-2440 1885);
PAINT MONO (-2440 1885);
DISPLAY INVISIBLE (-2440 1885);
FORCEPROP 1 LASTPIN (-2450 1875) BN 2
J 2
(-2438 1883);
DISPLAY 0.680851 (-2438 1883);
PAINT GREEN (-2438 1883);
FORCEPROP 2 LAST CDS_LIB standard
J 0
(-2500 1875);
DISPLAY INVISIBLE (-2500 1875);
FORCEPROP 1 LAST BODY_TYPE PLUMBING
J 2
(-2500 1925);
DISPLAY 0.872340 (-2500 1925);
PAINT GREEN (-2500 1925);
DISPLAY INVISIBLE (-2500 1925);
FORCEPROP 1 LAST HDL_TAP TRUE
J 2
(-2825 1750);
DISPLAY 0.872340 (-2825 1750);
DISPLAY INVISIBLE (-2825 1750);
FORCEPROP 1 LAST PATH I24
J 2
(-2498 1875);
DISPLAY 0.872340 (-2498 1875);
PAINT GREEN (-2498 1875);
DISPLAY INVISIBLE (-2498 1875);
FORCEADD TAP..1
R 2
(-2500 1825);
FORCEPROP 3 LASTPIN (-2450 1825) SIG_NAME M_H_CPU0_SB_CB<1>
J 0
(-2440 1835);
DISPLAY 0.659574 (-2440 1835);
PAINT MONO (-2440 1835);
DISPLAY INVISIBLE (-2440 1835);
FORCEPROP 1 LASTPIN (-2450 1825) BN 1
J 2
(-2438 1833);
DISPLAY 0.680851 (-2438 1833);
PAINT GREEN (-2438 1833);
FORCEPROP 2 LAST CDS_LIB standard
J 0
(-2500 1825);
DISPLAY INVISIBLE (-2500 1825);
FORCEPROP 1 LAST BODY_TYPE PLUMBING
J 2
(-2500 1875);
DISPLAY 0.872340 (-2500 1875);
PAINT GREEN (-2500 1875);
DISPLAY INVISIBLE (-2500 1875);
FORCEPROP 1 LAST HDL_TAP TRUE
J 2
(-2825 1700);
DISPLAY 0.872340 (-2825 1700);
DISPLAY INVISIBLE (-2825 1700);
FORCEPROP 1 LAST PATH I25
J 2
(-2498 1825);
DISPLAY 0.872340 (-2498 1825);
PAINT GREEN (-2498 1825);
DISPLAY INVISIBLE (-2498 1825);
FORCEADD TAP..1
R 2
(-2500 1925);
FORCEPROP 3 LASTPIN (-2450 1925) SIG_NAME M_H_CPU0_SB_CB<3>
J 0
(-2440 1935);
DISPLAY 0.659574 (-2440 1935);
PAINT MONO (-2440 1935);
DISPLAY INVISIBLE (-2440 1935);
FORCEPROP 1 LASTPIN (-2450 1925) BN 3
J 2
(-2438 1933);
DISPLAY 0.680851 (-2438 1933);
PAINT GREEN (-2438 1933);
FORCEPROP 2 LAST CDS_LIB standard
J 0
(-2500 1925);
DISPLAY INVISIBLE (-2500 1925);
FORCEPROP 1 LAST BODY_TYPE PLUMBING
J 2
(-2500 1975);
DISPLAY 0.872340 (-2500 1975);
PAINT GREEN (-2500 1975);
DISPLAY INVISIBLE (-2500 1975);
FORCEPROP 1 LAST HDL_TAP TRUE
J 2
(-2825 1800);
DISPLAY 0.872340 (-2825 1800);
DISPLAY INVISIBLE (-2825 1800);
FORCEPROP 1 LAST PATH I26
J 2
(-2498 1925);
DISPLAY 0.872340 (-2498 1925);
PAINT GREEN (-2498 1925);
DISPLAY INVISIBLE (-2498 1925);
FORCEADD TAP..1
R 2
(-2500 2025);
FORCEPROP 3 LASTPIN (-2450 2025) SIG_NAME M_H_CPU0_SB_CB<5>
J 0
(-2440 2035);
DISPLAY 0.659574 (-2440 2035);
PAINT MONO (-2440 2035);
DISPLAY INVISIBLE (-2440 2035);
FORCEPROP 1 LASTPIN (-2450 2025) BN 5
J 2
(-2438 2033);
DISPLAY 0.680851 (-2438 2033);
PAINT GREEN (-2438 2033);
FORCEPROP 2 LAST CDS_LIB standard
J 0
(-2500 2025);
DISPLAY INVISIBLE (-2500 2025);
FORCEPROP 1 LAST BODY_TYPE PLUMBING
J 2
(-2500 2075);
DISPLAY 0.872340 (-2500 2075);
PAINT GREEN (-2500 2075);
DISPLAY INVISIBLE (-2500 2075);
FORCEPROP 1 LAST HDL_TAP TRUE
J 2
(-2825 1900);
DISPLAY 0.872340 (-2825 1900);
DISPLAY INVISIBLE (-2825 1900);
FORCEPROP 1 LAST PATH I27
J 2
(-2498 2025);
DISPLAY 0.872340 (-2498 2025);
PAINT GREEN (-2498 2025);
DISPLAY INVISIBLE (-2498 2025);
FORCEADD TAP..1
R 2
(-2500 1975);
FORCEPROP 3 LASTPIN (-2450 1975) SIG_NAME M_H_CPU0_SB_CB<4>
J 0
(-2440 1985);
DISPLAY 0.659574 (-2440 1985);
PAINT MONO (-2440 1985);
DISPLAY INVISIBLE (-2440 1985);
FORCEPROP 1 LASTPIN (-2450 1975) BN 4
J 2
(-2438 1983);
DISPLAY 0.680851 (-2438 1983);
PAINT GREEN (-2438 1983);
FORCEPROP 2 LAST CDS_LIB standard
J 0
(-2500 1975);
DISPLAY INVISIBLE (-2500 1975);
FORCEPROP 1 LAST BODY_TYPE PLUMBING
J 2
(-2500 2025);
DISPLAY 0.872340 (-2500 2025);
PAINT GREEN (-2500 2025);
DISPLAY INVISIBLE (-2500 2025);
FORCEPROP 1 LAST HDL_TAP TRUE
J 2
(-2825 1850);
DISPLAY 0.872340 (-2825 1850);
DISPLAY INVISIBLE (-2825 1850);
FORCEPROP 1 LAST PATH I28
J 2
(-2498 1975);
DISPLAY 0.872340 (-2498 1975);
PAINT GREEN (-2498 1975);
DISPLAY INVISIBLE (-2498 1975);
FORCEADD TAP..1
R 2
(-2500 2075);
FORCEPROP 3 LASTPIN (-2450 2075) SIG_NAME M_H_CPU0_SB_CB<6>
J 0
(-2440 2085);
DISPLAY 0.659574 (-2440 2085);
PAINT MONO (-2440 2085);
DISPLAY INVISIBLE (-2440 2085);
FORCEPROP 1 LASTPIN (-2450 2075) BN 6
J 2
(-2438 2083);
DISPLAY 0.680851 (-2438 2083);
PAINT GREEN (-2438 2083);
FORCEPROP 2 LAST CDS_LIB standard
J 0
(-2500 2075);
DISPLAY INVISIBLE (-2500 2075);
FORCEPROP 1 LAST BODY_TYPE PLUMBING
J 2
(-2500 2125);
DISPLAY 0.872340 (-2500 2125);
PAINT GREEN (-2500 2125);
DISPLAY INVISIBLE (-2500 2125);
FORCEPROP 1 LAST HDL_TAP TRUE
J 2
(-2825 1950);
DISPLAY 0.872340 (-2825 1950);
DISPLAY INVISIBLE (-2825 1950);
FORCEPROP 1 LAST PATH I29
J 2
(-2498 2075);
DISPLAY 0.872340 (-2498 2075);
PAINT GREEN (-2498 2075);
DISPLAY INVISIBLE (-2498 2075);
FORCEADD OFFPAGE..2
R 2
(-3425 575);
FORCEPROP 2 LAST $XR0 27 
J 0
(-3649 575);
DISPLAY 0.638298 (-3649 575);
PAINT MONO (-3649 575);
FORCEPROP 2 LAST CDS_LIB standard
J 0
(-3425 575);
PAINT MONO (-3425 575);
DISPLAY INVISIBLE (-3425 575);
FORCEPROP 1 LAST OFFPAGE TRUE
J 2
(-3750 450);
DISPLAY 0.872340 (-3750 450);
DISPLAY INVISIBLE (-3750 450);
FORCEPROP 1 LAST COMMENT_BODY TRUE
J 2
(-3380 480);
DISPLAY 0.872340 (-3380 480);
PAINT GREEN (-3380 480);
DISPLAY INVISIBLE (-3380 480);
FORCEPROP 2 LAST PATH I3
J 0
(-3375 650);
DISPLAY 1.021277 (-3375 650);
DISPLAY INVISIBLE (-3375 650);
FORCEADD TAP..1
R 2
(-2500 2125);
FORCEPROP 3 LASTPIN (-2450 2125) SIG_NAME M_H_CPU0_SB_CB<7>
J 0
(-2440 2135);
DISPLAY 0.659574 (-2440 2135);
PAINT MONO (-2440 2135);
DISPLAY INVISIBLE (-2440 2135);
FORCEPROP 1 LASTPIN (-2450 2125) BN 7
J 2
(-2438 2133);
DISPLAY 0.680851 (-2438 2133);
PAINT GREEN (-2438 2133);
FORCEPROP 2 LAST CDS_LIB standard
J 0
(-2500 2125);
DISPLAY INVISIBLE (-2500 2125);
FORCEPROP 1 LAST BODY_TYPE PLUMBING
J 2
(-2500 2175);
DISPLAY 0.872340 (-2500 2175);
PAINT GREEN (-2500 2175);
DISPLAY INVISIBLE (-2500 2175);
FORCEPROP 1 LAST HDL_TAP TRUE
J 2
(-2825 2000);
DISPLAY 0.872340 (-2825 2000);
DISPLAY INVISIBLE (-2825 2000);
FORCEPROP 1 LAST PATH I30
J 2
(-2498 2125);
DISPLAY 0.872340 (-2498 2125);
PAINT GREEN (-2498 2125);
DISPLAY INVISIBLE (-2498 2125);
FORCEADD TAP..1
R 2
(-2500 2275);
FORCEPROP 3 LASTPIN (-2450 2275) SIG_NAME M_H_CPU0_SA_CB<1>
J 0
(-2440 2285);
DISPLAY 0.659574 (-2440 2285);
PAINT MONO (-2440 2285);
DISPLAY INVISIBLE (-2440 2285);
FORCEPROP 1 LASTPIN (-2450 2275) BN 1
J 2
(-2438 2283);
DISPLAY 0.680851 (-2438 2283);
PAINT GREEN (-2438 2283);
FORCEPROP 2 LAST CDS_LIB standard
J 0
(-2500 2275);
DISPLAY INVISIBLE (-2500 2275);
FORCEPROP 1 LAST BODY_TYPE PLUMBING
J 2
(-2500 2325);
DISPLAY 0.872340 (-2500 2325);
PAINT GREEN (-2500 2325);
DISPLAY INVISIBLE (-2500 2325);
FORCEPROP 1 LAST HDL_TAP TRUE
J 2
(-2825 2150);
DISPLAY 0.872340 (-2825 2150);
DISPLAY INVISIBLE (-2825 2150);
FORCEPROP 1 LAST PATH I31
J 2
(-2498 2275);
DISPLAY 0.872340 (-2498 2275);
PAINT GREEN (-2498 2275);
DISPLAY INVISIBLE (-2498 2275);
FORCEADD TAP..1
R 2
(-2500 2375);
FORCEPROP 3 LASTPIN (-2450 2375) SIG_NAME M_H_CPU0_SA_CB<3>
J 0
(-2440 2385);
DISPLAY 0.659574 (-2440 2385);
PAINT MONO (-2440 2385);
DISPLAY INVISIBLE (-2440 2385);
FORCEPROP 1 LASTPIN (-2450 2375) BN 3
J 2
(-2438 2383);
DISPLAY 0.680851 (-2438 2383);
PAINT GREEN (-2438 2383);
FORCEPROP 2 LAST CDS_LIB standard
J 0
(-2500 2375);
DISPLAY INVISIBLE (-2500 2375);
FORCEPROP 1 LAST BODY_TYPE PLUMBING
J 2
(-2500 2425);
DISPLAY 0.872340 (-2500 2425);
PAINT GREEN (-2500 2425);
DISPLAY INVISIBLE (-2500 2425);
FORCEPROP 1 LAST HDL_TAP TRUE
J 2
(-2825 2250);
DISPLAY 0.872340 (-2825 2250);
DISPLAY INVISIBLE (-2825 2250);
FORCEPROP 1 LAST PATH I32
J 2
(-2498 2375);
DISPLAY 0.872340 (-2498 2375);
PAINT GREEN (-2498 2375);
DISPLAY INVISIBLE (-2498 2375);
FORCEADD TAP..1
R 2
(-2500 2325);
FORCEPROP 3 LASTPIN (-2450 2325) SIG_NAME M_H_CPU0_SA_CB<2>
J 0
(-2440 2335);
DISPLAY 0.659574 (-2440 2335);
PAINT MONO (-2440 2335);
DISPLAY INVISIBLE (-2440 2335);
FORCEPROP 1 LASTPIN (-2450 2325) BN 2
J 2
(-2438 2333);
DISPLAY 0.680851 (-2438 2333);
PAINT GREEN (-2438 2333);
FORCEPROP 2 LAST CDS_LIB standard
J 0
(-2500 2325);
DISPLAY INVISIBLE (-2500 2325);
FORCEPROP 1 LAST BODY_TYPE PLUMBING
J 2
(-2500 2375);
DISPLAY 0.872340 (-2500 2375);
PAINT GREEN (-2500 2375);
DISPLAY INVISIBLE (-2500 2375);
FORCEPROP 1 LAST HDL_TAP TRUE
J 2
(-2825 2200);
DISPLAY 0.872340 (-2825 2200);
DISPLAY INVISIBLE (-2825 2200);
FORCEPROP 1 LAST PATH I33
J 2
(-2498 2325);
DISPLAY 0.872340 (-2498 2325);
PAINT GREEN (-2498 2325);
DISPLAY INVISIBLE (-2498 2325);
FORCEADD TAP..1
R 2
(-2500 2225);
FORCEPROP 3 LASTPIN (-2450 2225) SIG_NAME M_H_CPU0_SA_CB<0>
J 0
(-2440 2235);
DISPLAY 0.659574 (-2440 2235);
PAINT MONO (-2440 2235);
DISPLAY INVISIBLE (-2440 2235);
FORCEPROP 1 LASTPIN (-2450 2225) BN 0
J 2
(-2438 2233);
DISPLAY 0.680851 (-2438 2233);
PAINT GREEN (-2438 2233);
FORCEPROP 2 LAST CDS_LIB standard
J 0
(-2500 2225);
PAINT MONO (-2500 2225);
DISPLAY INVISIBLE (-2500 2225);
FORCEPROP 1 LAST BODY_TYPE PLUMBING
J 2
(-2500 2275);
DISPLAY 0.872340 (-2500 2275);
PAINT GREEN (-2500 2275);
DISPLAY INVISIBLE (-2500 2275);
FORCEPROP 1 LAST HDL_TAP TRUE
J 2
(-2825 2100);
DISPLAY 0.872340 (-2825 2100);
DISPLAY INVISIBLE (-2825 2100);
FORCEPROP 1 LAST PATH I34
J 2
(-2498 2225);
DISPLAY 0.872340 (-2498 2225);
PAINT GREEN (-2498 2225);
DISPLAY INVISIBLE (-2498 2225);
FORCEADD TAP..1
R 2
(-2500 2425);
FORCEPROP 3 LASTPIN (-2450 2425) SIG_NAME M_H_CPU0_SA_CB<4>
J 0
(-2440 2435);
DISPLAY 0.659574 (-2440 2435);
PAINT MONO (-2440 2435);
DISPLAY INVISIBLE (-2440 2435);
FORCEPROP 1 LASTPIN (-2450 2425) BN 4
J 2
(-2438 2433);
DISPLAY 0.680851 (-2438 2433);
PAINT GREEN (-2438 2433);
FORCEPROP 2 LAST CDS_LIB standard
J 0
(-2500 2425);
DISPLAY INVISIBLE (-2500 2425);
FORCEPROP 1 LAST BODY_TYPE PLUMBING
J 2
(-2500 2475);
DISPLAY 0.872340 (-2500 2475);
PAINT GREEN (-2500 2475);
DISPLAY INVISIBLE (-2500 2475);
FORCEPROP 1 LAST HDL_TAP TRUE
J 2
(-2825 2300);
DISPLAY 0.872340 (-2825 2300);
DISPLAY INVISIBLE (-2825 2300);
FORCEPROP 1 LAST PATH I35
J 2
(-2498 2425);
DISPLAY 0.872340 (-2498 2425);
PAINT GREEN (-2498 2425);
DISPLAY INVISIBLE (-2498 2425);
FORCEADD TAP..1
R 2
(-2500 2525);
FORCEPROP 3 LASTPIN (-2450 2525) SIG_NAME M_H_CPU0_SA_CB<6>
J 0
(-2440 2535);
DISPLAY 0.659574 (-2440 2535);
PAINT MONO (-2440 2535);
DISPLAY INVISIBLE (-2440 2535);
FORCEPROP 1 LASTPIN (-2450 2525) BN 6
J 2
(-2438 2533);
DISPLAY 0.680851 (-2438 2533);
PAINT GREEN (-2438 2533);
FORCEPROP 2 LAST CDS_LIB standard
J 0
(-2500 2525);
DISPLAY INVISIBLE (-2500 2525);
FORCEPROP 1 LAST BODY_TYPE PLUMBING
J 2
(-2500 2575);
DISPLAY 0.872340 (-2500 2575);
PAINT GREEN (-2500 2575);
DISPLAY INVISIBLE (-2500 2575);
FORCEPROP 1 LAST HDL_TAP TRUE
J 2
(-2825 2400);
DISPLAY 0.872340 (-2825 2400);
DISPLAY INVISIBLE (-2825 2400);
FORCEPROP 1 LAST PATH I36
J 2
(-2498 2525);
DISPLAY 0.872340 (-2498 2525);
PAINT GREEN (-2498 2525);
DISPLAY INVISIBLE (-2498 2525);
FORCEADD TAP..1
R 2
(-2500 2575);
FORCEPROP 3 LASTPIN (-2450 2575) SIG_NAME M_H_CPU0_SA_CB<7>
J 0
(-2440 2585);
DISPLAY 0.659574 (-2440 2585);
PAINT MONO (-2440 2585);
DISPLAY INVISIBLE (-2440 2585);
FORCEPROP 1 LASTPIN (-2450 2575) BN 7
J 2
(-2438 2583);
DISPLAY 0.680851 (-2438 2583);
PAINT GREEN (-2438 2583);
FORCEPROP 2 LAST CDS_LIB standard
J 0
(-2500 2575);
DISPLAY INVISIBLE (-2500 2575);
FORCEPROP 1 LAST BODY_TYPE PLUMBING
J 2
(-2500 2625);
DISPLAY 0.872340 (-2500 2625);
PAINT GREEN (-2500 2625);
DISPLAY INVISIBLE (-2500 2625);
FORCEPROP 1 LAST HDL_TAP TRUE
J 2
(-2825 2450);
DISPLAY 0.872340 (-2825 2450);
DISPLAY INVISIBLE (-2825 2450);
FORCEPROP 1 LAST PATH I37
J 2
(-2498 2575);
DISPLAY 0.872340 (-2498 2575);
PAINT GREEN (-2498 2575);
DISPLAY INVISIBLE (-2498 2575);
FORCEADD TAP..1
R 2
(-2500 2475);
FORCEPROP 3 LASTPIN (-2450 2475) SIG_NAME M_H_CPU0_SA_CB<5>
J 0
(-2440 2485);
DISPLAY 0.659574 (-2440 2485);
PAINT MONO (-2440 2485);
DISPLAY INVISIBLE (-2440 2485);
FORCEPROP 1 LASTPIN (-2450 2475) BN 5
J 2
(-2438 2483);
DISPLAY 0.680851 (-2438 2483);
PAINT GREEN (-2438 2483);
FORCEPROP 2 LAST CDS_LIB standard
J 0
(-2500 2475);
DISPLAY INVISIBLE (-2500 2475);
FORCEPROP 1 LAST BODY_TYPE PLUMBING
J 2
(-2500 2525);
DISPLAY 0.872340 (-2500 2525);
PAINT GREEN (-2500 2525);
DISPLAY INVISIBLE (-2500 2525);
FORCEPROP 1 LAST HDL_TAP TRUE
J 2
(-2825 2350);
DISPLAY 0.872340 (-2825 2350);
DISPLAY INVISIBLE (-2825 2350);
FORCEPROP 1 LAST PATH I38
J 2
(-2498 2475);
DISPLAY 0.872340 (-2498 2475);
PAINT GREEN (-2498 2475);
DISPLAY INVISIBLE (-2498 2475);
FORCEADD TAP..1
R 2
(-2500 3425);
FORCEPROP 3 LASTPIN (-2450 3425) SIG_NAME M_H_CPU0_SB_CA<3>
J 0
(-2440 3435);
DISPLAY 0.659574 (-2440 3435);
PAINT MONO (-2440 3435);
DISPLAY INVISIBLE (-2440 3435);
FORCEPROP 1 LASTPIN (-2450 3425) BN 3
J 2
(-2438 3433);
DISPLAY 0.680851 (-2438 3433);
PAINT GREEN (-2438 3433);
FORCEPROP 2 LAST CDS_LIB standard
J 0
(-2500 3425);
DISPLAY INVISIBLE (-2500 3425);
FORCEPROP 1 LAST BODY_TYPE PLUMBING
J 2
(-2500 3475);
DISPLAY 0.872340 (-2500 3475);
PAINT GREEN (-2500 3475);
DISPLAY INVISIBLE (-2500 3475);
FORCEPROP 1 LAST HDL_TAP TRUE
J 2
(-2825 3300);
DISPLAY 0.872340 (-2825 3300);
DISPLAY INVISIBLE (-2825 3300);
FORCEPROP 1 LAST PATH I39
J 2
(-2498 3425);
DISPLAY 0.872340 (-2498 3425);
PAINT GREEN (-2498 3425);
DISPLAY INVISIBLE (-2498 3425);
FORCEADD OFFPAGE..2
R 2
(-3425 525);
FORCEPROP 2 LAST $XR0 27 
J 0
(-3649 525);
DISPLAY 0.638298 (-3649 525);
PAINT MONO (-3649 525);
FORCEPROP 2 LAST CDS_LIB standard
J 0
(-3425 525);
PAINT MONO (-3425 525);
DISPLAY INVISIBLE (-3425 525);
FORCEPROP 1 LAST OFFPAGE TRUE
J 2
(-3750 400);
DISPLAY 0.872340 (-3750 400);
DISPLAY INVISIBLE (-3750 400);
FORCEPROP 1 LAST COMMENT_BODY TRUE
J 2
(-3380 430);
DISPLAY 0.872340 (-3380 430);
PAINT GREEN (-3380 430);
DISPLAY INVISIBLE (-3380 430);
FORCEPROP 2 LAST PATH I4
J 0
(-3375 600);
DISPLAY 1.021277 (-3375 600);
DISPLAY INVISIBLE (-3375 600);
FORCEADD TAP..1
R 2
(-2500 3325);
FORCEPROP 3 LASTPIN (-2450 3325) SIG_NAME M_H_CPU0_SB_CA<1>
J 0
(-2440 3335);
DISPLAY 0.659574 (-2440 3335);
PAINT MONO (-2440 3335);
DISPLAY INVISIBLE (-2440 3335);
FORCEPROP 1 LASTPIN (-2450 3325) BN 1
J 2
(-2438 3333);
DISPLAY 0.680851 (-2438 3333);
PAINT GREEN (-2438 3333);
FORCEPROP 2 LAST CDS_LIB standard
J 0
(-2500 3325);
DISPLAY INVISIBLE (-2500 3325);
FORCEPROP 1 LAST BODY_TYPE PLUMBING
J 2
(-2500 3375);
DISPLAY 0.872340 (-2500 3375);
PAINT GREEN (-2500 3375);
DISPLAY INVISIBLE (-2500 3375);
FORCEPROP 1 LAST HDL_TAP TRUE
J 2
(-2825 3200);
DISPLAY 0.872340 (-2825 3200);
DISPLAY INVISIBLE (-2825 3200);
FORCEPROP 1 LAST PATH I40
J 2
(-2498 3325);
DISPLAY 0.872340 (-2498 3325);
PAINT GREEN (-2498 3325);
DISPLAY INVISIBLE (-2498 3325);
FORCEADD TAP..1
R 2
(-2500 3375);
FORCEPROP 3 LASTPIN (-2450 3375) SIG_NAME M_H_CPU0_SB_CA<2>
J 0
(-2440 3385);
DISPLAY 0.659574 (-2440 3385);
PAINT MONO (-2440 3385);
DISPLAY INVISIBLE (-2440 3385);
FORCEPROP 1 LASTPIN (-2450 3375) BN 2
J 2
(-2438 3383);
DISPLAY 0.680851 (-2438 3383);
PAINT GREEN (-2438 3383);
FORCEPROP 2 LAST CDS_LIB standard
J 0
(-2500 3375);
DISPLAY INVISIBLE (-2500 3375);
FORCEPROP 1 LAST BODY_TYPE PLUMBING
J 2
(-2500 3425);
DISPLAY 0.872340 (-2500 3425);
PAINT GREEN (-2500 3425);
DISPLAY INVISIBLE (-2500 3425);
FORCEPROP 1 LAST HDL_TAP TRUE
J 2
(-2825 3250);
DISPLAY 0.872340 (-2825 3250);
DISPLAY INVISIBLE (-2825 3250);
FORCEPROP 1 LAST PATH I41
J 2
(-2498 3375);
DISPLAY 0.872340 (-2498 3375);
PAINT GREEN (-2498 3375);
DISPLAY INVISIBLE (-2498 3375);
FORCEADD TAP..1
R 2
(-2500 3275);
FORCEPROP 3 LASTPIN (-2450 3275) SIG_NAME M_H_CPU0_SB_CA<0>
J 0
(-2440 3285);
DISPLAY 0.659574 (-2440 3285);
PAINT MONO (-2440 3285);
DISPLAY INVISIBLE (-2440 3285);
FORCEPROP 1 LASTPIN (-2450 3275) BN 0
J 2
(-2438 3283);
DISPLAY 0.680851 (-2438 3283);
PAINT GREEN (-2438 3283);
FORCEPROP 2 LAST CDS_LIB standard
J 0
(-2500 3275);
DISPLAY INVISIBLE (-2500 3275);
FORCEPROP 1 LAST BODY_TYPE PLUMBING
J 2
(-2500 3325);
DISPLAY 0.872340 (-2500 3325);
PAINT GREEN (-2500 3325);
DISPLAY INVISIBLE (-2500 3325);
FORCEPROP 1 LAST HDL_TAP TRUE
J 2
(-2825 3150);
DISPLAY 0.872340 (-2825 3150);
DISPLAY INVISIBLE (-2825 3150);
FORCEPROP 1 LAST PATH I42
J 2
(-2498 3275);
DISPLAY 0.872340 (-2498 3275);
PAINT GREEN (-2498 3275);
DISPLAY INVISIBLE (-2498 3275);
FORCEADD TAP..1
R 2
(-2500 3575);
FORCEPROP 3 LASTPIN (-2450 3575) SIG_NAME M_H_CPU0_SB_CA<6>
J 0
(-2440 3585);
DISPLAY 0.659574 (-2440 3585);
PAINT MONO (-2440 3585);
DISPLAY INVISIBLE (-2440 3585);
FORCEPROP 1 LASTPIN (-2450 3575) BN 6
J 2
(-2438 3583);
DISPLAY 0.680851 (-2438 3583);
PAINT GREEN (-2438 3583);
FORCEPROP 2 LAST CDS_LIB standard
J 0
(-2500 3575);
DISPLAY INVISIBLE (-2500 3575);
FORCEPROP 1 LAST BODY_TYPE PLUMBING
J 2
(-2500 3625);
DISPLAY 0.872340 (-2500 3625);
PAINT GREEN (-2500 3625);
DISPLAY INVISIBLE (-2500 3625);
FORCEPROP 1 LAST HDL_TAP TRUE
J 2
(-2825 3450);
DISPLAY 0.872340 (-2825 3450);
DISPLAY INVISIBLE (-2825 3450);
FORCEPROP 1 LAST PATH I43
J 2
(-2498 3575);
DISPLAY 0.872340 (-2498 3575);
PAINT GREEN (-2498 3575);
DISPLAY INVISIBLE (-2498 3575);
FORCEADD TAP..1
R 2
(-2500 3525);
FORCEPROP 3 LASTPIN (-2450 3525) SIG_NAME M_H_CPU0_SB_CA<5>
J 0
(-2440 3535);
DISPLAY 0.659574 (-2440 3535);
PAINT MONO (-2440 3535);
DISPLAY INVISIBLE (-2440 3535);
FORCEPROP 1 LASTPIN (-2450 3525) BN 5
J 2
(-2438 3533);
DISPLAY 0.680851 (-2438 3533);
PAINT GREEN (-2438 3533);
FORCEPROP 2 LAST CDS_LIB standard
J 0
(-2500 3525);
DISPLAY INVISIBLE (-2500 3525);
FORCEPROP 1 LAST BODY_TYPE PLUMBING
J 2
(-2500 3575);
DISPLAY 0.872340 (-2500 3575);
PAINT GREEN (-2500 3575);
DISPLAY INVISIBLE (-2500 3575);
FORCEPROP 1 LAST HDL_TAP TRUE
J 2
(-2825 3400);
DISPLAY 0.872340 (-2825 3400);
DISPLAY INVISIBLE (-2825 3400);
FORCEPROP 1 LAST PATH I44
J 2
(-2498 3525);
DISPLAY 0.872340 (-2498 3525);
PAINT GREEN (-2498 3525);
DISPLAY INVISIBLE (-2498 3525);
FORCEADD TAP..1
R 2
(-2500 3475);
FORCEPROP 3 LASTPIN (-2450 3475) SIG_NAME M_H_CPU0_SB_CA<4>
J 0
(-2440 3485);
DISPLAY 0.659574 (-2440 3485);
PAINT MONO (-2440 3485);
DISPLAY INVISIBLE (-2440 3485);
FORCEPROP 1 LASTPIN (-2450 3475) BN 4
J 2
(-2438 3483);
DISPLAY 0.680851 (-2438 3483);
PAINT GREEN (-2438 3483);
FORCEPROP 2 LAST CDS_LIB standard
J 0
(-2500 3475);
DISPLAY INVISIBLE (-2500 3475);
FORCEPROP 1 LAST BODY_TYPE PLUMBING
J 2
(-2500 3525);
DISPLAY 0.872340 (-2500 3525);
PAINT GREEN (-2500 3525);
DISPLAY INVISIBLE (-2500 3525);
FORCEPROP 1 LAST HDL_TAP TRUE
J 2
(-2825 3350);
DISPLAY 0.872340 (-2825 3350);
DISPLAY INVISIBLE (-2825 3350);
FORCEPROP 1 LAST PATH I45
J 2
(-2498 3475);
DISPLAY 0.872340 (-2498 3475);
PAINT GREEN (-2498 3475);
DISPLAY INVISIBLE (-2498 3475);
FORCEADD TAP..1
R 2
(-2500 3675);
FORCEPROP 3 LASTPIN (-2450 3675) SIG_NAME M_H_CPU0_SA_CA<0>
J 0
(-2440 3685);
DISPLAY 0.659574 (-2440 3685);
PAINT MONO (-2440 3685);
DISPLAY INVISIBLE (-2440 3685);
FORCEPROP 1 LASTPIN (-2450 3675) BN 0
J 2
(-2438 3683);
DISPLAY 0.680851 (-2438 3683);
PAINT GREEN (-2438 3683);
FORCEPROP 2 LAST CDS_LIB standard
J 0
(-2500 3675);
DISPLAY INVISIBLE (-2500 3675);
FORCEPROP 1 LAST BODY_TYPE PLUMBING
J 2
(-2500 3725);
DISPLAY 0.872340 (-2500 3725);
PAINT GREEN (-2500 3725);
DISPLAY INVISIBLE (-2500 3725);
FORCEPROP 1 LAST HDL_TAP TRUE
J 2
(-2825 3550);
DISPLAY 0.872340 (-2825 3550);
DISPLAY INVISIBLE (-2825 3550);
FORCEPROP 1 LAST PATH I46
J 2
(-2498 3675);
DISPLAY 0.872340 (-2498 3675);
PAINT GREEN (-2498 3675);
DISPLAY INVISIBLE (-2498 3675);
FORCEADD Q_RES..2
(-2275 -175);
FORCEPROP 1 LAST PART_NUMBER CS41272FB07
J 0
(-2235 -300);
DISPLAY 0.978723 (-2235 -300);
DISPLAY INVISIBLE (-2235 -300);
FORCEPROP 1 LAST VALUE 127K
J 0
(-2230 -100);
DISPLAY 0.978723 (-2230 -100);
FORCEPROP 1 LAST MATERIAL CHIP
J 0
(-2235 -250);
DISPLAY 0.978723 (-2235 -250);
FORCEPROP 1 LAST TOLERANCE 1%
J 0
(-2230 -150);
DISPLAY 0.978723 (-2230 -150);
FORCEPROP 1 LAST PACK_TYPE 0402LF
J 0
(-2235 -350);
DISPLAY 0.978723 (-2235 -350);
FORCEPROP 1 LAST WATTAGE 1/16W
J 0
(-2235 -200);
DISPLAY 0.978723 (-2235 -200);
FORCEPROP 1 LAST $LOCATION R40
J 0
(-2230 -50);
DISPLAY 0.978723 (-2230 -50);
FORCEPROP 1 LASTPIN (-2275 -75) $PN 1
J 0
(-2270 -113);
DISPLAY 0.787234 (-2270 -113);
FORCEPROP 1 LASTPIN (-2275 -275) $PN 2
J 0
(-2270 -265);
DISPLAY 0.787234 (-2270 -265);
FORCEPROP 2 LAST CDS_LIB pure_quanta
J 0
(-2275 -175);
PAINT MONO (-2275 -175);
DISPLAY INVISIBLE (-2275 -175);
FORCEPROP 2 LAST CDS_LOCATION R40
J 0
(-2225 50);
DISPLAY 1.021277 (-2225 50);
DISPLAY INVISIBLE (-2225 50);
FORCEPROP 2 LAST $SEC 1
J 0
(-2225 50);
DISPLAY 0.680851 (-2225 50);
PAINT MONO (-2225 50);
DISPLAY INVISIBLE (-2225 50);
FORCEPROP 2 LAST CDS_SEC 1
J 0
(-2225 50);
DISPLAY 1.021277 (-2225 50);
DISPLAY INVISIBLE (-2225 50);
FORCEPROP 1 LAST PATH I47
J 0
(-2225 0);
DISPLAY 0.978723 (-2225 0);
PAINT WHITE (-2225 0);
DISPLAY INVISIBLE (-2225 0);
FORCEADD SCONN288_ADR50017P130CC..1
(-1675 2250);
FORCEPROP 1 LAST PART_NUMBER DFHST8FS461
J 0
(-2120 4272);
DISPLAY 0.723404 (-2120 4272);
PAINT GREEN (-2120 4272);
DISPLAY INVISIBLE (-2120 4272);
FORCEPROP 1 LAST MATERIAL IO
J 0
(-2120 4145);
DISPLAY 0.723404 (-2120 4145);
PAINT GREEN (-2120 4145);
FORCEPROP 2 LAST PART_TYPE SMLF
J 0
(-2125 4450);
DISPLAY 1.021277 (-2125 4450);
FORCEPROP 2 LAST VALUE SCONN288_ADR50017-P130CC
J 0
(-2125 4375);
DISPLAY 1.021277 (-2125 4375);
FORCEPROP 1 LAST $LOCATION J15
J 0
(-2125 4325);
DISPLAY 0.723404 (-2125 4325);
PAINT GREEN (-2125 4325);
FORCEPROP 0 LASTPIN (-2275 1625) $PN 62
J 2
(-2285 1635);
DISPLAY 0.680851 (-2285 1635);
PAINT MONO (-2285 1635);
FORCEPROP 0 LASTPIN (-2275 3675) $PN 66
J 2
(-2285 3685);
DISPLAY 0.680851 (-2285 3685);
PAINT MONO (-2285 3685);
FORCEPROP 0 LASTPIN (-2275 3275) $PN 76
J 2
(-2285 3285);
DISPLAY 0.680851 (-2285 3285);
PAINT MONO (-2285 3285);
FORCEPROP 0 LASTPIN (-2275 3725) $PN 211
J 2
(-2285 3735);
DISPLAY 0.680851 (-2285 3735);
PAINT MONO (-2285 3735);
FORCEPROP 0 LASTPIN (-2275 3325) $PN 221
J 2
(-2285 3335);
DISPLAY 0.680851 (-2285 3335);
PAINT MONO (-2285 3335);
FORCEPROP 0 LASTPIN (-2275 3775) $PN 68
J 2
(-2285 3785);
DISPLAY 0.680851 (-2285 3785);
PAINT MONO (-2285 3785);
FORCEPROP 0 LASTPIN (-2275 3375) $PN 78
J 2
(-2285 3385);
DISPLAY 0.680851 (-2285 3385);
PAINT MONO (-2285 3385);
FORCEPROP 0 LASTPIN (-2275 3825) $PN 213
J 2
(-2285 3835);
DISPLAY 0.680851 (-2285 3835);
PAINT MONO (-2285 3835);
FORCEPROP 0 LASTPIN (-2275 3425) $PN 223
J 2
(-2285 3435);
DISPLAY 0.680851 (-2285 3435);
PAINT MONO (-2285 3435);
FORCEPROP 0 LASTPIN (-2275 3875) $PN 70
J 2
(-2285 3885);
DISPLAY 0.680851 (-2285 3885);
PAINT MONO (-2285 3885);
FORCEPROP 0 LASTPIN (-2275 3475) $PN 80
J 2
(-2285 3485);
DISPLAY 0.680851 (-2285 3485);
PAINT MONO (-2285 3485);
FORCEPROP 0 LASTPIN (-2275 3925) $PN 215
J 2
(-2285 3935);
DISPLAY 0.680851 (-2285 3935);
PAINT MONO (-2285 3935);
FORCEPROP 0 LASTPIN (-2275 3525) $PN 225
J 2
(-2285 3535);
DISPLAY 0.680851 (-2285 3535);
PAINT MONO (-2285 3535);
FORCEPROP 0 LASTPIN (-2275 3975) $PN 72
J 2
(-2285 3985);
DISPLAY 0.680851 (-2285 3985);
PAINT MONO (-2285 3985);
FORCEPROP 0 LASTPIN (-2275 3575) $PN 82
J 2
(-2285 3585);
DISPLAY 0.680851 (-2285 3585);
PAINT MONO (-2285 3585);
FORCEPROP 0 LASTPIN (-2275 2225) $PN 51
J 2
(-2285 2235);
DISPLAY 0.680851 (-2285 2235);
PAINT MONO (-2285 2235);
FORCEPROP 0 LASTPIN (-2275 1775) $PN 96
J 2
(-2285 1785);
DISPLAY 0.680851 (-2285 1785);
PAINT MONO (-2285 1785);
FORCEPROP 0 LASTPIN (-2275 2275) $PN 53
J 2
(-2285 2285);
DISPLAY 0.680851 (-2285 2285);
PAINT MONO (-2285 2285);
FORCEPROP 0 LASTPIN (-2275 1825) $PN 98
J 2
(-2285 1835);
DISPLAY 0.680851 (-2285 1835);
PAINT MONO (-2285 1835);
FORCEPROP 0 LASTPIN (-2275 2325) $PN 196
J 2
(-2285 2335);
DISPLAY 0.680851 (-2285 2335);
PAINT MONO (-2285 2335);
FORCEPROP 0 LASTPIN (-2275 1875) $PN 241
J 2
(-2285 1885);
DISPLAY 0.680851 (-2285 1885);
PAINT MONO (-2285 1885);
FORCEPROP 0 LASTPIN (-2275 2375) $PN 198
J 2
(-2285 2385);
DISPLAY 0.680851 (-2285 2385);
PAINT MONO (-2285 2385);
FORCEPROP 0 LASTPIN (-2275 1925) $PN 243
J 2
(-2285 1935);
DISPLAY 0.680851 (-2285 1935);
PAINT MONO (-2285 1935);
FORCEPROP 0 LASTPIN (-2275 2425) $PN 58
J 2
(-2285 2435);
DISPLAY 0.680851 (-2285 2435);
PAINT MONO (-2285 2435);
FORCEPROP 0 LASTPIN (-2275 1975) $PN 89
J 2
(-2285 1985);
DISPLAY 0.680851 (-2285 1985);
PAINT MONO (-2285 1985);
FORCEPROP 0 LASTPIN (-2275 2475) $PN 60
J 2
(-2285 2485);
DISPLAY 0.680851 (-2285 2485);
PAINT MONO (-2285 2485);
FORCEPROP 0 LASTPIN (-2275 2025) $PN 91
J 2
(-2285 2035);
DISPLAY 0.680851 (-2285 2035);
PAINT MONO (-2285 2035);
FORCEPROP 0 LASTPIN (-2275 2525) $PN 203
J 2
(-2285 2535);
DISPLAY 0.680851 (-2285 2535);
PAINT MONO (-2285 2535);
FORCEPROP 0 LASTPIN (-2275 2075) $PN 234
J 2
(-2285 2085);
DISPLAY 0.680851 (-2285 2085);
PAINT MONO (-2285 2085);
FORCEPROP 0 LASTPIN (-2275 2575) $PN 205
J 2
(-2285 2585);
DISPLAY 0.680851 (-2285 2585);
PAINT MONO (-2285 2585);
FORCEPROP 0 LASTPIN (-2275 2125) $PN 236
J 2
(-2285 2135);
DISPLAY 0.680851 (-2285 2135);
PAINT MONO (-2285 2135);
FORCEPROP 0 LASTPIN (-2275 2675) $PN 218
J 2
(-2285 2685);
DISPLAY 0.680851 (-2285 2685);
PAINT MONO (-2285 2685);
FORCEPROP 0 LASTPIN (-2275 2725) $PN 217
J 2
(-2285 2735);
DISPLAY 0.680851 (-2285 2735);
PAINT MONO (-2285 2735);
FORCEPROP 0 LASTPIN (-2275 2975) $PN 64
J 2
(-2285 2985);
DISPLAY 0.680851 (-2285 2985);
PAINT MONO (-2285 2985);
FORCEPROP 0 LASTPIN (-2275 2825) $PN 84
J 2
(-2285 2835);
DISPLAY 0.680851 (-2285 2835);
PAINT MONO (-2285 2835);
FORCEPROP 0 LASTPIN (-2275 3025) $PN 209
J 2
(-2285 3035);
DISPLAY 0.680851 (-2285 3035);
PAINT MONO (-2285 3035);
FORCEPROP 0 LASTPIN (-2275 2875) $PN 229
J 2
(-2285 2885);
DISPLAY 0.680851 (-2285 2885);
PAINT MONO (-2285 2885);
FORCEPROP 0 LASTPIN (-1075 2425) $PN 7
J 0
(-1065 2435);
DISPLAY 0.680851 (-1065 2435);
PAINT MONO (-1065 2435);
FORCEPROP 0 LASTPIN (-1075 775) $PN 100
J 0
(-1065 785);
DISPLAY 0.680851 (-1065 785);
PAINT MONO (-1065 785);
FORCEPROP 0 LASTPIN (-1075 2475) $PN 9
J 0
(-1065 2485);
DISPLAY 0.680851 (-1065 2485);
PAINT MONO (-1065 2485);
FORCEPROP 0 LASTPIN (-1075 825) $PN 102
J 0
(-1065 835);
DISPLAY 0.680851 (-1065 835);
PAINT MONO (-1065 835);
FORCEPROP 0 LASTPIN (-1075 2525) $PN 152
J 0
(-1065 2535);
DISPLAY 0.680851 (-1065 2535);
PAINT MONO (-1065 2535);
FORCEPROP 0 LASTPIN (-1075 875) $PN 245
J 0
(-1065 885);
DISPLAY 0.680851 (-1065 885);
PAINT MONO (-1065 885);
FORCEPROP 0 LASTPIN (-1075 2575) $PN 154
J 0
(-1065 2585);
DISPLAY 0.680851 (-1065 2585);
PAINT MONO (-1065 2585);
FORCEPROP 0 LASTPIN (-1075 925) $PN 247
J 0
(-1065 935);
DISPLAY 0.680851 (-1065 935);
PAINT MONO (-1065 935);
FORCEPROP 0 LASTPIN (-1075 2625) $PN 14
J 0
(-1065 2635);
DISPLAY 0.680851 (-1065 2635);
PAINT MONO (-1065 2635);
FORCEPROP 0 LASTPIN (-1075 975) $PN 107
J 0
(-1065 985);
DISPLAY 0.680851 (-1065 985);
PAINT MONO (-1065 985);
FORCEPROP 0 LASTPIN (-1075 2675) $PN 16
J 0
(-1065 2685);
DISPLAY 0.680851 (-1065 2685);
PAINT MONO (-1065 2685);
FORCEPROP 0 LASTPIN (-1075 1025) $PN 109
J 0
(-1065 1035);
DISPLAY 0.680851 (-1065 1035);
PAINT MONO (-1065 1035);
FORCEPROP 0 LASTPIN (-1075 2725) $PN 159
J 0
(-1065 2735);
DISPLAY 0.680851 (-1065 2735);
PAINT MONO (-1065 2735);
FORCEPROP 0 LASTPIN (-1075 1075) $PN 252
J 0
(-1065 1085);
DISPLAY 0.680851 (-1065 1085);
PAINT MONO (-1065 1085);
FORCEPROP 0 LASTPIN (-1075 2775) $PN 161
J 0
(-1065 2785);
DISPLAY 0.680851 (-1065 2785);
PAINT MONO (-1065 2785);
FORCEPROP 0 LASTPIN (-1075 1125) $PN 254
J 0
(-1065 1135);
DISPLAY 0.680851 (-1065 1135);
PAINT MONO (-1065 1135);
FORCEPROP 0 LASTPIN (-1075 2825) $PN 18
J 0
(-1065 2835);
DISPLAY 0.680851 (-1065 2835);
PAINT MONO (-1065 2835);
FORCEPROP 0 LASTPIN (-1075 1175) $PN 111
J 0
(-1065 1185);
DISPLAY 0.680851 (-1065 1185);
PAINT MONO (-1065 1185);
FORCEPROP 0 LASTPIN (-1075 2875) $PN 20
J 0
(-1065 2885);
DISPLAY 0.680851 (-1065 2885);
PAINT MONO (-1065 2885);
FORCEPROP 0 LASTPIN (-1075 1225) $PN 113
J 0
(-1065 1235);
DISPLAY 0.680851 (-1065 1235);
PAINT MONO (-1065 1235);
FORCEPROP 0 LASTPIN (-1075 2925) $PN 163
J 0
(-1065 2935);
DISPLAY 0.680851 (-1065 2935);
PAINT MONO (-1065 2935);
FORCEPROP 0 LASTPIN (-1075 1275) $PN 256
J 0
(-1065 1285);
DISPLAY 0.680851 (-1065 1285);
PAINT MONO (-1065 1285);
FORCEPROP 0 LASTPIN (-1075 2975) $PN 165
J 0
(-1065 2985);
DISPLAY 0.680851 (-1065 2985);
PAINT MONO (-1065 2985);
FORCEPROP 0 LASTPIN (-1075 1325) $PN 258
J 0
(-1065 1335);
DISPLAY 0.680851 (-1065 1335);
PAINT MONO (-1065 1335);
FORCEPROP 0 LASTPIN (-1075 3025) $PN 25
J 0
(-1065 3035);
DISPLAY 0.680851 (-1065 3035);
PAINT MONO (-1065 3035);
FORCEPROP 0 LASTPIN (-1075 1375) $PN 118
J 0
(-1065 1385);
DISPLAY 0.680851 (-1065 1385);
PAINT MONO (-1065 1385);
FORCEPROP 0 LASTPIN (-1075 3075) $PN 27
J 0
(-1065 3085);
DISPLAY 0.680851 (-1065 3085);
PAINT MONO (-1065 3085);
FORCEPROP 0 LASTPIN (-1075 1425) $PN 120
J 0
(-1065 1435);
DISPLAY 0.680851 (-1065 1435);
PAINT MONO (-1065 1435);
FORCEPROP 0 LASTPIN (-1075 3125) $PN 170
J 0
(-1065 3135);
DISPLAY 0.680851 (-1065 3135);
PAINT MONO (-1065 3135);
FORCEPROP 0 LASTPIN (-1075 1475) $PN 263
J 0
(-1065 1485);
DISPLAY 0.680851 (-1065 1485);
PAINT MONO (-1065 1485);
FORCEPROP 0 LASTPIN (-1075 3175) $PN 172
J 0
(-1065 3185);
DISPLAY 0.680851 (-1065 3185);
PAINT MONO (-1065 3185);
FORCEPROP 0 LASTPIN (-1075 1525) $PN 265
J 0
(-1065 1535);
DISPLAY 0.680851 (-1065 1535);
PAINT MONO (-1065 1535);
FORCEPROP 0 LASTPIN (-1075 3225) $PN 29
J 0
(-1065 3235);
DISPLAY 0.680851 (-1065 3235);
PAINT MONO (-1065 3235);
FORCEPROP 0 LASTPIN (-1075 1575) $PN 122
J 0
(-1065 1585);
DISPLAY 0.680851 (-1065 1585);
PAINT MONO (-1065 1585);
FORCEPROP 0 LASTPIN (-1075 3275) $PN 31
J 0
(-1065 3285);
DISPLAY 0.680851 (-1065 3285);
PAINT MONO (-1065 3285);
FORCEPROP 0 LASTPIN (-1075 1625) $PN 124
J 0
(-1065 1635);
DISPLAY 0.680851 (-1065 1635);
PAINT MONO (-1065 1635);
FORCEPROP 0 LASTPIN (-1075 3325) $PN 174
J 0
(-1065 3335);
DISPLAY 0.680851 (-1065 3335);
PAINT MONO (-1065 3335);
FORCEPROP 0 LASTPIN (-1075 1675) $PN 267
J 0
(-1065 1685);
DISPLAY 0.680851 (-1065 1685);
PAINT MONO (-1065 1685);
FORCEPROP 0 LASTPIN (-1075 3375) $PN 176
J 0
(-1065 3385);
DISPLAY 0.680851 (-1065 3385);
PAINT MONO (-1065 3385);
FORCEPROP 0 LASTPIN (-1075 1725) $PN 269
J 0
(-1065 1735);
DISPLAY 0.680851 (-1065 1735);
PAINT MONO (-1065 1735);
FORCEPROP 0 LASTPIN (-1075 3425) $PN 36
J 0
(-1065 3435);
DISPLAY 0.680851 (-1065 3435);
PAINT MONO (-1065 3435);
FORCEPROP 0 LASTPIN (-1075 1775) $PN 129
J 0
(-1065 1785);
DISPLAY 0.680851 (-1065 1785);
PAINT MONO (-1065 1785);
FORCEPROP 0 LASTPIN (-1075 3475) $PN 38
J 0
(-1065 3485);
DISPLAY 0.680851 (-1065 3485);
PAINT MONO (-1065 3485);
FORCEPROP 0 LASTPIN (-1075 1825) $PN 131
J 0
(-1065 1835);
DISPLAY 0.680851 (-1065 1835);
PAINT MONO (-1065 1835);
FORCEPROP 0 LASTPIN (-1075 3525) $PN 181
J 0
(-1065 3535);
DISPLAY 0.680851 (-1065 3535);
PAINT MONO (-1065 3535);
FORCEPROP 0 LASTPIN (-1075 1875) $PN 274
J 0
(-1065 1885);
DISPLAY 0.680851 (-1065 1885);
PAINT MONO (-1065 1885);
FORCEPROP 0 LASTPIN (-1075 3575) $PN 183
J 0
(-1065 3585);
DISPLAY 0.680851 (-1065 3585);
PAINT MONO (-1065 3585);
FORCEPROP 0 LASTPIN (-1075 1925) $PN 276
J 0
(-1065 1935);
DISPLAY 0.680851 (-1065 1935);
PAINT MONO (-1065 1935);
FORCEPROP 0 LASTPIN (-1075 3625) $PN 40
J 0
(-1065 3635);
DISPLAY 0.680851 (-1065 3635);
PAINT MONO (-1065 3635);
FORCEPROP 0 LASTPIN (-1075 1975) $PN 133
J 0
(-1065 1985);
DISPLAY 0.680851 (-1065 1985);
PAINT MONO (-1065 1985);
FORCEPROP 0 LASTPIN (-1075 3675) $PN 42
J 0
(-1065 3685);
DISPLAY 0.680851 (-1065 3685);
PAINT MONO (-1065 3685);
FORCEPROP 0 LASTPIN (-1075 2025) $PN 135
J 0
(-1065 2035);
DISPLAY 0.680851 (-1065 2035);
PAINT MONO (-1065 2035);
FORCEPROP 0 LASTPIN (-1075 3725) $PN 185
J 0
(-1065 3735);
DISPLAY 0.680851 (-1065 3735);
PAINT MONO (-1065 3735);
FORCEPROP 0 LASTPIN (-1075 2075) $PN 278
J 0
(-1065 2085);
DISPLAY 0.680851 (-1065 2085);
PAINT MONO (-1065 2085);
FORCEPROP 0 LASTPIN (-1075 3775) $PN 187
J 0
(-1065 3785);
DISPLAY 0.680851 (-1065 3785);
PAINT MONO (-1065 3785);
FORCEPROP 0 LASTPIN (-1075 2125) $PN 280
J 0
(-1065 2135);
DISPLAY 0.680851 (-1065 2135);
PAINT MONO (-1065 2135);
FORCEPROP 0 LASTPIN (-1075 3825) $PN 47
J 0
(-1065 3835);
DISPLAY 0.680851 (-1065 3835);
PAINT MONO (-1065 3835);
FORCEPROP 0 LASTPIN (-1075 2175) $PN 140
J 0
(-1065 2185);
DISPLAY 0.680851 (-1065 2185);
PAINT MONO (-1065 2185);
FORCEPROP 0 LASTPIN (-1075 3875) $PN 49
J 0
(-1065 3885);
DISPLAY 0.680851 (-1065 3885);
PAINT MONO (-1065 3885);
FORCEPROP 0 LASTPIN (-1075 2225) $PN 142
J 0
(-1065 2235);
DISPLAY 0.680851 (-1065 2235);
PAINT MONO (-1065 2235);
FORCEPROP 0 LASTPIN (-1075 3925) $PN 192
J 0
(-1065 3935);
DISPLAY 0.680851 (-1065 3935);
PAINT MONO (-1065 3935);
FORCEPROP 0 LASTPIN (-1075 2275) $PN 285
J 0
(-1065 2285);
DISPLAY 0.680851 (-1065 2285);
PAINT MONO (-1065 2285);
FORCEPROP 0 LASTPIN (-1075 3975) $PN 194
J 0
(-1065 3985);
DISPLAY 0.680851 (-1065 3985);
PAINT MONO (-1065 3985);
FORCEPROP 0 LASTPIN (-1075 2325) $PN 287
J 0
(-1065 2335);
DISPLAY 0.680851 (-1065 2335);
PAINT MONO (-1065 2335);
FORCEPROP 0 LASTPIN (-2275 1475) $PN 148
J 2
(-2285 1485);
DISPLAY 0.680851 (-2285 1485);
PAINT MONO (-2285 1485);
FORCEPROP 0 LASTPIN (-2275 1375) $PN 4
J 2
(-2285 1385);
DISPLAY 0.680851 (-2285 1385);
PAINT MONO (-2285 1385);
FORCEPROP 0 LASTPIN (-2275 1425) $PN 5
J 2
(-2285 1435);
DISPLAY 0.680851 (-2285 1435);
PAINT MONO (-2285 1435);
FORCEPROP 0 LASTPIN (-2275 575) $PN 86
J 2
(-2285 585);
DISPLAY 0.680851 (-2285 585);
PAINT MONO (-2285 585);
FORCEPROP 0 LASTPIN (-2275 525) $PN 87
J 2
(-2285 535);
DISPLAY 0.680851 (-2285 535);
PAINT MONO (-2285 535);
FORCEPROP 0 LASTPIN (-2275 3175) $PN 74
J 2
(-2285 3185);
DISPLAY 0.680851 (-2285 3185);
PAINT MONO (-2285 3185);
FORCEPROP 0 LASTPIN (-2275 3125) $PN 227
J 2
(-2285 3135);
DISPLAY 0.680851 (-2285 3135);
PAINT MONO (-2285 3135);
FORCEPROP 0 LASTPIN (-2275 1125) $PN 147
J 2
(-2285 1135);
DISPLAY 0.680851 (-2285 1135);
PAINT MONO (-2285 1135);
FORCEPROP 0 LASTPIN (-2275 1675) $PN 207
J 2
(-2285 1685);
DISPLAY 0.680851 (-2285 1685);
PAINT MONO (-2285 1685);
FORCEPROP 0 LASTPIN (-2275 725) $PN 2
J 2
(-2285 735);
DISPLAY 0.680851 (-2285 735);
PAINT MONO (-2285 735);
FORCEPROP 0 LASTPIN (-2275 775) $PN 144
J 2
(-2285 785);
DISPLAY 0.680851 (-2285 785);
PAINT MONO (-2285 785);
FORCEPROP 0 LASTPIN (-2275 825) $PN 149
J 2
(-2285 835);
DISPLAY 0.680851 (-2285 835);
PAINT MONO (-2285 835);
FORCEPROP 0 LASTPIN (-2275 875) $PN 150
J 2
(-2285 885);
DISPLAY 0.680851 (-2285 885);
PAINT MONO (-2285 885);
FORCEPROP 0 LASTPIN (-2275 925) $PN 220
J 2
(-2285 935);
DISPLAY 0.680851 (-2285 935);
PAINT MONO (-2285 935);
FORCEPROP 0 LASTPIN (-2275 975) $PN 231
J 2
(-2285 985);
DISPLAY 0.680851 (-2285 985);
PAINT MONO (-2285 985);
FORCEPROP 0 LASTPIN (-2275 1025) $PN 232
J 2
(-2285 1035);
DISPLAY 0.680851 (-2285 1035);
PAINT MONO (-2285 1035);
FORCEPROP 0 LASTPIN (-2275 1525) $PN 3
J 2
(-2285 1535);
DISPLAY 0.680851 (-2285 1535);
PAINT MONO (-2285 1535);
FORCEPROP 1 LAST NEEDS_NO_SIZE TRUE
J 0
(-1675 2250);
DISPLAY 0.723404 (-1675 2250);
PAINT GREEN (-1675 2250);
DISPLAY INVISIBLE (-1675 2250);
FORCEPROP 1 LAST CDS_LMAN_SYM_OUTLINE -450,1875,450,-1875
J 0
(-1675 2250);
DISPLAY 0.468085 (-1675 2250);
PAINT GREEN (-1675 2250);
DISPLAY INVISIBLE (-1675 2250);
FORCEPROP 2 LAST CDS_LIB pure_quanta
J 0
(-1675 2250);
DISPLAY INVISIBLE (-1675 2250);
FORCEPROP 2 LAST CDS_LOCATION J15
J 0
(-2125 4475);
DISPLAY 1.021277 (-2125 4475);
DISPLAY INVISIBLE (-2125 4475);
FORCEPROP 0 LAST $SEC 1
J 0
(-2100 4475);
DISPLAY 0.680851 (-2100 4475);
PAINT MONO (-2100 4475);
DISPLAY INVISIBLE (-2100 4475);
FORCEPROP 2 LAST CDS_SEC 1
J 0
(-2125 4475);
DISPLAY 1.021277 (-2125 4475);
DISPLAY INVISIBLE (-2125 4475);
FORCEPROP 1 LAST PATH I48
J 0
(-1675 2250);
DISPLAY 0.723404 (-1675 2250);
PAINT GREEN (-1675 2250);
DISPLAY INVISIBLE (-1675 2250);
FORCEADD TAP..1
(-850 775);
FORCEPROP 3 LASTPIN (-900 775) SIG_NAME M_H_CPU0_SB_DQ<0>
J 0
(-890 785);
DISPLAY 0.659574 (-890 785);
PAINT MONO (-890 785);
DISPLAY INVISIBLE (-890 785);
FORCEPROP 1 LASTPIN (-900 775) BN 0
J 0
(-912 783);
DISPLAY 0.680851 (-912 783);
PAINT GREEN (-912 783);
FORCEPROP 2 LAST CDS_LIB standard
J 0
(-850 775);
PAINT MONO (-850 775);
DISPLAY INVISIBLE (-850 775);
FORCEPROP 1 LAST BODY_TYPE PLUMBING
J 0
(-850 825);
DISPLAY 0.872340 (-850 825);
PAINT GREEN (-850 825);
DISPLAY INVISIBLE (-850 825);
FORCEPROP 1 LAST HDL_TAP TRUE
J 0
(-525 650);
DISPLAY 0.872340 (-525 650);
DISPLAY INVISIBLE (-525 650);
FORCEPROP 1 LAST PATH I49
J 0
(-852 775);
DISPLAY 0.872340 (-852 775);
PAINT GREEN (-852 775);
DISPLAY INVISIBLE (-852 775);
FORCEADD OFFPAGE..3
R 2
(-3425 1125);
FORCEPROP 2 LAST $XR0 114 
J 0
(-3705 1125);
DISPLAY 0.638298 (-3705 1125);
PAINT MONO (-3705 1125);
FORCEPROP 2 LAST CDS_LIB standard
J 0
(-3425 1125);
PAINT MONO (-3425 1125);
DISPLAY INVISIBLE (-3425 1125);
FORCEPROP 1 LAST OFFPAGE TRUE
J 2
(-3750 1000);
DISPLAY 0.872340 (-3750 1000);
DISPLAY INVISIBLE (-3750 1000);
FORCEPROP 1 LAST COMMENT_BODY TRUE
J 2
(-3375 1025);
DISPLAY 0.872340 (-3375 1025);
PAINT GREEN (-3375 1025);
DISPLAY INVISIBLE (-3375 1025);
FORCEPROP 2 LAST PATH I5
J 0
(-3375 1200);
DISPLAY 1.021277 (-3375 1200);
DISPLAY INVISIBLE (-3375 1200);
FORCEADD TAP..1
(-850 875);
FORCEPROP 3 LASTPIN (-900 875) SIG_NAME M_H_CPU0_SB_DQ<2>
J 0
(-890 885);
DISPLAY 0.659574 (-890 885);
PAINT MONO (-890 885);
DISPLAY INVISIBLE (-890 885);
FORCEPROP 1 LASTPIN (-900 875) BN 2
J 0
(-912 883);
DISPLAY 0.680851 (-912 883);
PAINT GREEN (-912 883);
FORCEPROP 2 LAST CDS_LIB standard
J 0
(-850 875);
PAINT MONO (-850 875);
DISPLAY INVISIBLE (-850 875);
FORCEPROP 1 LAST BODY_TYPE PLUMBING
J 0
(-850 925);
DISPLAY 0.872340 (-850 925);
PAINT GREEN (-850 925);
DISPLAY INVISIBLE (-850 925);
FORCEPROP 1 LAST HDL_TAP TRUE
J 0
(-525 750);
DISPLAY 0.872340 (-525 750);
DISPLAY INVISIBLE (-525 750);
FORCEPROP 1 LAST PATH I50
J 0
(-852 875);
DISPLAY 0.872340 (-852 875);
PAINT GREEN (-852 875);
DISPLAY INVISIBLE (-852 875);
FORCEADD TAP..1
(-850 825);
FORCEPROP 3 LASTPIN (-900 825) SIG_NAME M_H_CPU0_SB_DQ<1>
J 0
(-890 835);
DISPLAY 0.659574 (-890 835);
PAINT MONO (-890 835);
DISPLAY INVISIBLE (-890 835);
FORCEPROP 1 LASTPIN (-900 825) BN 1
J 0
(-912 833);
DISPLAY 0.680851 (-912 833);
PAINT GREEN (-912 833);
FORCEPROP 2 LAST CDS_LIB standard
J 0
(-850 825);
PAINT MONO (-850 825);
DISPLAY INVISIBLE (-850 825);
FORCEPROP 1 LAST BODY_TYPE PLUMBING
J 0
(-850 875);
DISPLAY 0.872340 (-850 875);
PAINT GREEN (-850 875);
DISPLAY INVISIBLE (-850 875);
FORCEPROP 1 LAST HDL_TAP TRUE
J 0
(-525 700);
DISPLAY 0.872340 (-525 700);
DISPLAY INVISIBLE (-525 700);
FORCEPROP 1 LAST PATH I51
J 0
(-852 825);
DISPLAY 0.872340 (-852 825);
PAINT GREEN (-852 825);
DISPLAY INVISIBLE (-852 825);
FORCEADD TAP..1
(-850 925);
FORCEPROP 3 LASTPIN (-900 925) SIG_NAME M_H_CPU0_SB_DQ<3>
J 0
(-890 935);
DISPLAY 0.659574 (-890 935);
PAINT MONO (-890 935);
DISPLAY INVISIBLE (-890 935);
FORCEPROP 1 LASTPIN (-900 925) BN 3
J 0
(-912 933);
DISPLAY 0.680851 (-912 933);
PAINT GREEN (-912 933);
FORCEPROP 2 LAST CDS_LIB standard
J 0
(-850 925);
PAINT MONO (-850 925);
DISPLAY INVISIBLE (-850 925);
FORCEPROP 1 LAST BODY_TYPE PLUMBING
J 0
(-850 975);
DISPLAY 0.872340 (-850 975);
PAINT GREEN (-850 975);
DISPLAY INVISIBLE (-850 975);
FORCEPROP 1 LAST HDL_TAP TRUE
J 0
(-525 800);
DISPLAY 0.872340 (-525 800);
DISPLAY INVISIBLE (-525 800);
FORCEPROP 1 LAST PATH I52
J 0
(-852 925);
DISPLAY 0.872340 (-852 925);
PAINT GREEN (-852 925);
DISPLAY INVISIBLE (-852 925);
FORCEADD TAP..1
(-850 1025);
FORCEPROP 3 LASTPIN (-900 1025) SIG_NAME M_H_CPU0_SB_DQ<5>
J 0
(-890 1035);
DISPLAY 0.659574 (-890 1035);
PAINT MONO (-890 1035);
DISPLAY INVISIBLE (-890 1035);
FORCEPROP 1 LASTPIN (-900 1025) BN 5
J 0
(-912 1033);
DISPLAY 0.680851 (-912 1033);
PAINT GREEN (-912 1033);
FORCEPROP 2 LAST CDS_LIB standard
J 0
(-850 1025);
PAINT MONO (-850 1025);
DISPLAY INVISIBLE (-850 1025);
FORCEPROP 1 LAST BODY_TYPE PLUMBING
J 0
(-850 1075);
DISPLAY 0.872340 (-850 1075);
PAINT GREEN (-850 1075);
DISPLAY INVISIBLE (-850 1075);
FORCEPROP 1 LAST HDL_TAP TRUE
J 0
(-525 900);
DISPLAY 0.872340 (-525 900);
DISPLAY INVISIBLE (-525 900);
FORCEPROP 1 LAST PATH I53
J 0
(-852 1025);
DISPLAY 0.872340 (-852 1025);
PAINT GREEN (-852 1025);
DISPLAY INVISIBLE (-852 1025);
FORCEADD TAP..1
(-850 975);
FORCEPROP 3 LASTPIN (-900 975) SIG_NAME M_H_CPU0_SB_DQ<4>
J 0
(-890 985);
DISPLAY 0.659574 (-890 985);
PAINT MONO (-890 985);
DISPLAY INVISIBLE (-890 985);
FORCEPROP 1 LASTPIN (-900 975) BN 4
J 0
(-912 983);
DISPLAY 0.680851 (-912 983);
PAINT GREEN (-912 983);
FORCEPROP 2 LAST CDS_LIB standard
J 0
(-850 975);
PAINT MONO (-850 975);
DISPLAY INVISIBLE (-850 975);
FORCEPROP 1 LAST BODY_TYPE PLUMBING
J 0
(-850 1025);
DISPLAY 0.872340 (-850 1025);
PAINT GREEN (-850 1025);
DISPLAY INVISIBLE (-850 1025);
FORCEPROP 1 LAST HDL_TAP TRUE
J 0
(-525 850);
DISPLAY 0.872340 (-525 850);
DISPLAY INVISIBLE (-525 850);
FORCEPROP 1 LAST PATH I54
J 0
(-852 975);
DISPLAY 0.872340 (-852 975);
PAINT GREEN (-852 975);
DISPLAY INVISIBLE (-852 975);
FORCEADD TAP..1
(-850 1075);
FORCEPROP 3 LASTPIN (-900 1075) SIG_NAME M_H_CPU0_SB_DQ<6>
J 0
(-890 1085);
DISPLAY 0.659574 (-890 1085);
PAINT MONO (-890 1085);
DISPLAY INVISIBLE (-890 1085);
FORCEPROP 1 LASTPIN (-900 1075) BN 6
J 0
(-912 1083);
DISPLAY 0.680851 (-912 1083);
PAINT GREEN (-912 1083);
FORCEPROP 2 LAST CDS_LIB standard
J 0
(-850 1075);
PAINT MONO (-850 1075);
DISPLAY INVISIBLE (-850 1075);
FORCEPROP 1 LAST BODY_TYPE PLUMBING
J 0
(-850 1125);
DISPLAY 0.872340 (-850 1125);
PAINT GREEN (-850 1125);
DISPLAY INVISIBLE (-850 1125);
FORCEPROP 1 LAST HDL_TAP TRUE
J 0
(-525 950);
DISPLAY 0.872340 (-525 950);
DISPLAY INVISIBLE (-525 950);
FORCEPROP 1 LAST PATH I55
J 0
(-852 1075);
DISPLAY 0.872340 (-852 1075);
PAINT GREEN (-852 1075);
DISPLAY INVISIBLE (-852 1075);
FORCEADD TAP..1
(-850 1125);
FORCEPROP 3 LASTPIN (-900 1125) SIG_NAME M_H_CPU0_SB_DQ<7>
J 0
(-890 1135);
DISPLAY 0.659574 (-890 1135);
PAINT MONO (-890 1135);
DISPLAY INVISIBLE (-890 1135);
FORCEPROP 1 LASTPIN (-900 1125) BN 7
J 0
(-912 1133);
DISPLAY 0.680851 (-912 1133);
PAINT GREEN (-912 1133);
FORCEPROP 2 LAST CDS_LIB standard
J 0
(-850 1125);
PAINT MONO (-850 1125);
DISPLAY INVISIBLE (-850 1125);
FORCEPROP 1 LAST BODY_TYPE PLUMBING
J 0
(-850 1175);
DISPLAY 0.872340 (-850 1175);
PAINT GREEN (-850 1175);
DISPLAY INVISIBLE (-850 1175);
FORCEPROP 1 LAST HDL_TAP TRUE
J 0
(-525 1000);
DISPLAY 0.872340 (-525 1000);
DISPLAY INVISIBLE (-525 1000);
FORCEPROP 1 LAST PATH I56
J 0
(-852 1125);
DISPLAY 0.872340 (-852 1125);
PAINT GREEN (-852 1125);
DISPLAY INVISIBLE (-852 1125);
FORCEADD TAP..1
(-850 1175);
FORCEPROP 3 LASTPIN (-900 1175) SIG_NAME M_H_CPU0_SB_DQ<8>
J 0
(-890 1185);
DISPLAY 0.659574 (-890 1185);
PAINT MONO (-890 1185);
DISPLAY INVISIBLE (-890 1185);
FORCEPROP 1 LASTPIN (-900 1175) BN 8
J 0
(-912 1183);
DISPLAY 0.680851 (-912 1183);
PAINT GREEN (-912 1183);
FORCEPROP 2 LAST CDS_LIB standard
J 0
(-850 1175);
PAINT MONO (-850 1175);
DISPLAY INVISIBLE (-850 1175);
FORCEPROP 1 LAST BODY_TYPE PLUMBING
J 0
(-850 1225);
DISPLAY 0.872340 (-850 1225);
PAINT GREEN (-850 1225);
DISPLAY INVISIBLE (-850 1225);
FORCEPROP 1 LAST HDL_TAP TRUE
J 0
(-525 1050);
DISPLAY 0.872340 (-525 1050);
DISPLAY INVISIBLE (-525 1050);
FORCEPROP 1 LAST PATH I57
J 0
(-852 1175);
DISPLAY 0.872340 (-852 1175);
PAINT GREEN (-852 1175);
DISPLAY INVISIBLE (-852 1175);
FORCEADD TAP..1
(-850 1225);
FORCEPROP 3 LASTPIN (-900 1225) SIG_NAME M_H_CPU0_SB_DQ<9>
J 0
(-890 1235);
DISPLAY 0.659574 (-890 1235);
PAINT MONO (-890 1235);
DISPLAY INVISIBLE (-890 1235);
FORCEPROP 1 LASTPIN (-900 1225) BN 9
J 0
(-912 1233);
DISPLAY 0.680851 (-912 1233);
PAINT GREEN (-912 1233);
FORCEPROP 2 LAST CDS_LIB standard
J 0
(-850 1225);
PAINT MONO (-850 1225);
DISPLAY INVISIBLE (-850 1225);
FORCEPROP 1 LAST BODY_TYPE PLUMBING
J 0
(-850 1275);
DISPLAY 0.872340 (-850 1275);
PAINT GREEN (-850 1275);
DISPLAY INVISIBLE (-850 1275);
FORCEPROP 1 LAST HDL_TAP TRUE
J 0
(-525 1100);
DISPLAY 0.872340 (-525 1100);
DISPLAY INVISIBLE (-525 1100);
FORCEPROP 1 LAST PATH I58
J 0
(-852 1225);
DISPLAY 0.872340 (-852 1225);
PAINT GREEN (-852 1225);
DISPLAY INVISIBLE (-852 1225);
FORCEADD TAP..1
(-850 1275);
FORCEPROP 3 LASTPIN (-900 1275) SIG_NAME M_H_CPU0_SB_DQ<10>
J 0
(-890 1285);
DISPLAY 0.659574 (-890 1285);
PAINT MONO (-890 1285);
DISPLAY INVISIBLE (-890 1285);
FORCEPROP 1 LASTPIN (-900 1275) BN 10
J 0
(-912 1283);
DISPLAY 0.680851 (-912 1283);
PAINT GREEN (-912 1283);
FORCEPROP 2 LAST CDS_LIB standard
J 0
(-850 1275);
PAINT MONO (-850 1275);
DISPLAY INVISIBLE (-850 1275);
FORCEPROP 1 LAST BODY_TYPE PLUMBING
J 0
(-850 1325);
DISPLAY 0.872340 (-850 1325);
PAINT GREEN (-850 1325);
DISPLAY INVISIBLE (-850 1325);
FORCEPROP 1 LAST HDL_TAP TRUE
J 0
(-525 1150);
DISPLAY 0.872340 (-525 1150);
DISPLAY INVISIBLE (-525 1150);
FORCEPROP 1 LAST PATH I59
J 0
(-852 1275);
DISPLAY 0.872340 (-852 1275);
PAINT GREEN (-852 1275);
DISPLAY INVISIBLE (-852 1275);
FORCEADD TAP..1
(-850 1375);
FORCEPROP 3 LASTPIN (-900 1375) SIG_NAME M_H_CPU0_SB_DQ<12>
J 0
(-890 1385);
DISPLAY 0.659574 (-890 1385);
PAINT MONO (-890 1385);
DISPLAY INVISIBLE (-890 1385);
FORCEPROP 1 LASTPIN (-900 1375) BN 12
J 0
(-912 1383);
DISPLAY 0.680851 (-912 1383);
PAINT GREEN (-912 1383);
FORCEPROP 2 LAST CDS_LIB standard
J 0
(-850 1375);
PAINT MONO (-850 1375);
DISPLAY INVISIBLE (-850 1375);
FORCEPROP 1 LAST BODY_TYPE PLUMBING
J 0
(-850 1425);
DISPLAY 0.872340 (-850 1425);
PAINT GREEN (-850 1425);
DISPLAY INVISIBLE (-850 1425);
FORCEPROP 1 LAST HDL_TAP TRUE
J 0
(-525 1250);
DISPLAY 0.872340 (-525 1250);
DISPLAY INVISIBLE (-525 1250);
FORCEPROP 1 LAST PATH I60
J 0
(-852 1375);
DISPLAY 0.872340 (-852 1375);
PAINT GREEN (-852 1375);
DISPLAY INVISIBLE (-852 1375);
FORCEADD TAP..1
(-850 1325);
FORCEPROP 3 LASTPIN (-900 1325) SIG_NAME M_H_CPU0_SB_DQ<11>
J 0
(-890 1335);
DISPLAY 0.659574 (-890 1335);
PAINT MONO (-890 1335);
DISPLAY INVISIBLE (-890 1335);
FORCEPROP 1 LASTPIN (-900 1325) BN 11
J 0
(-912 1333);
DISPLAY 0.680851 (-912 1333);
PAINT GREEN (-912 1333);
FORCEPROP 2 LAST CDS_LIB standard
J 0
(-850 1325);
PAINT MONO (-850 1325);
DISPLAY INVISIBLE (-850 1325);
FORCEPROP 1 LAST BODY_TYPE PLUMBING
J 0
(-850 1375);
DISPLAY 0.872340 (-850 1375);
PAINT GREEN (-850 1375);
DISPLAY INVISIBLE (-850 1375);
FORCEPROP 1 LAST HDL_TAP TRUE
J 0
(-525 1200);
DISPLAY 0.872340 (-525 1200);
DISPLAY INVISIBLE (-525 1200);
FORCEPROP 1 LAST PATH I61
J 0
(-852 1325);
DISPLAY 0.872340 (-852 1325);
PAINT GREEN (-852 1325);
DISPLAY INVISIBLE (-852 1325);
FORCEADD TAP..1
(-850 1425);
FORCEPROP 3 LASTPIN (-900 1425) SIG_NAME M_H_CPU0_SB_DQ<13>
J 0
(-890 1435);
DISPLAY 0.659574 (-890 1435);
PAINT MONO (-890 1435);
DISPLAY INVISIBLE (-890 1435);
FORCEPROP 1 LASTPIN (-900 1425) BN 13
J 0
(-912 1433);
DISPLAY 0.680851 (-912 1433);
PAINT GREEN (-912 1433);
FORCEPROP 2 LAST CDS_LIB standard
J 0
(-850 1425);
PAINT MONO (-850 1425);
DISPLAY INVISIBLE (-850 1425);
FORCEPROP 1 LAST BODY_TYPE PLUMBING
J 0
(-850 1475);
DISPLAY 0.872340 (-850 1475);
PAINT GREEN (-850 1475);
DISPLAY INVISIBLE (-850 1475);
FORCEPROP 1 LAST HDL_TAP TRUE
J 0
(-525 1300);
DISPLAY 0.872340 (-525 1300);
DISPLAY INVISIBLE (-525 1300);
FORCEPROP 1 LAST PATH I62
J 0
(-852 1425);
DISPLAY 0.872340 (-852 1425);
PAINT GREEN (-852 1425);
DISPLAY INVISIBLE (-852 1425);
FORCEADD TAP..1
(-850 1475);
FORCEPROP 3 LASTPIN (-900 1475) SIG_NAME M_H_CPU0_SB_DQ<14>
J 0
(-890 1485);
DISPLAY 0.659574 (-890 1485);
PAINT MONO (-890 1485);
DISPLAY INVISIBLE (-890 1485);
FORCEPROP 1 LASTPIN (-900 1475) BN 14
J 0
(-912 1483);
DISPLAY 0.680851 (-912 1483);
PAINT GREEN (-912 1483);
FORCEPROP 2 LAST CDS_LIB standard
J 0
(-850 1475);
PAINT MONO (-850 1475);
DISPLAY INVISIBLE (-850 1475);
FORCEPROP 1 LAST BODY_TYPE PLUMBING
J 0
(-850 1525);
DISPLAY 0.872340 (-850 1525);
PAINT GREEN (-850 1525);
DISPLAY INVISIBLE (-850 1525);
FORCEPROP 1 LAST HDL_TAP TRUE
J 0
(-525 1350);
DISPLAY 0.872340 (-525 1350);
DISPLAY INVISIBLE (-525 1350);
FORCEPROP 1 LAST PATH I63
J 0
(-852 1475);
DISPLAY 0.872340 (-852 1475);
PAINT GREEN (-852 1475);
DISPLAY INVISIBLE (-852 1475);
FORCEADD TAP..1
(-850 1525);
FORCEPROP 3 LASTPIN (-900 1525) SIG_NAME M_H_CPU0_SB_DQ<15>
J 0
(-890 1535);
DISPLAY 0.659574 (-890 1535);
PAINT MONO (-890 1535);
DISPLAY INVISIBLE (-890 1535);
FORCEPROP 1 LASTPIN (-900 1525) BN 15
J 0
(-912 1533);
DISPLAY 0.680851 (-912 1533);
PAINT GREEN (-912 1533);
FORCEPROP 2 LAST CDS_LIB standard
J 0
(-850 1525);
PAINT MONO (-850 1525);
DISPLAY INVISIBLE (-850 1525);
FORCEPROP 1 LAST BODY_TYPE PLUMBING
J 0
(-850 1575);
DISPLAY 0.872340 (-850 1575);
PAINT GREEN (-850 1575);
DISPLAY INVISIBLE (-850 1575);
FORCEPROP 1 LAST HDL_TAP TRUE
J 0
(-525 1400);
DISPLAY 0.872340 (-525 1400);
DISPLAY INVISIBLE (-525 1400);
FORCEPROP 1 LAST PATH I64
J 0
(-852 1525);
DISPLAY 0.872340 (-852 1525);
PAINT GREEN (-852 1525);
DISPLAY INVISIBLE (-852 1525);
FORCEADD TAP..1
(-850 1625);
FORCEPROP 3 LASTPIN (-900 1625) SIG_NAME M_H_CPU0_SB_DQ<17>
J 0
(-890 1635);
DISPLAY 0.659574 (-890 1635);
PAINT MONO (-890 1635);
DISPLAY INVISIBLE (-890 1635);
FORCEPROP 1 LASTPIN (-900 1625) BN 17
J 0
(-912 1633);
DISPLAY 0.680851 (-912 1633);
PAINT GREEN (-912 1633);
FORCEPROP 2 LAST CDS_LIB standard
J 0
(-850 1625);
PAINT MONO (-850 1625);
DISPLAY INVISIBLE (-850 1625);
FORCEPROP 1 LAST BODY_TYPE PLUMBING
J 0
(-850 1675);
DISPLAY 0.872340 (-850 1675);
PAINT GREEN (-850 1675);
DISPLAY INVISIBLE (-850 1675);
FORCEPROP 1 LAST HDL_TAP TRUE
J 0
(-525 1500);
DISPLAY 0.872340 (-525 1500);
DISPLAY INVISIBLE (-525 1500);
FORCEPROP 1 LAST PATH I65
J 0
(-852 1625);
DISPLAY 0.872340 (-852 1625);
PAINT GREEN (-852 1625);
DISPLAY INVISIBLE (-852 1625);
FORCEADD TAP..1
(-850 1575);
FORCEPROP 3 LASTPIN (-900 1575) SIG_NAME M_H_CPU0_SB_DQ<16>
J 0
(-890 1585);
DISPLAY 0.659574 (-890 1585);
PAINT MONO (-890 1585);
DISPLAY INVISIBLE (-890 1585);
FORCEPROP 1 LASTPIN (-900 1575) BN 16
J 0
(-912 1583);
DISPLAY 0.680851 (-912 1583);
PAINT GREEN (-912 1583);
FORCEPROP 2 LAST CDS_LIB standard
J 0
(-850 1575);
PAINT MONO (-850 1575);
DISPLAY INVISIBLE (-850 1575);
FORCEPROP 1 LAST BODY_TYPE PLUMBING
J 0
(-850 1625);
DISPLAY 0.872340 (-850 1625);
PAINT GREEN (-850 1625);
DISPLAY INVISIBLE (-850 1625);
FORCEPROP 1 LAST HDL_TAP TRUE
J 0
(-525 1450);
DISPLAY 0.872340 (-525 1450);
DISPLAY INVISIBLE (-525 1450);
FORCEPROP 1 LAST PATH I66
J 0
(-852 1575);
DISPLAY 0.872340 (-852 1575);
PAINT GREEN (-852 1575);
DISPLAY INVISIBLE (-852 1575);
FORCEADD TAP..1
(-850 1725);
FORCEPROP 3 LASTPIN (-900 1725) SIG_NAME M_H_CPU0_SB_DQ<19>
J 0
(-890 1735);
DISPLAY 0.659574 (-890 1735);
PAINT MONO (-890 1735);
DISPLAY INVISIBLE (-890 1735);
FORCEPROP 1 LASTPIN (-900 1725) BN 19
J 0
(-912 1733);
DISPLAY 0.680851 (-912 1733);
PAINT GREEN (-912 1733);
FORCEPROP 2 LAST CDS_LIB standard
J 0
(-850 1725);
PAINT MONO (-850 1725);
DISPLAY INVISIBLE (-850 1725);
FORCEPROP 1 LAST BODY_TYPE PLUMBING
J 0
(-850 1775);
DISPLAY 0.872340 (-850 1775);
PAINT GREEN (-850 1775);
DISPLAY INVISIBLE (-850 1775);
FORCEPROP 1 LAST HDL_TAP TRUE
J 0
(-525 1600);
DISPLAY 0.872340 (-525 1600);
DISPLAY INVISIBLE (-525 1600);
FORCEPROP 1 LAST PATH I67
J 0
(-852 1725);
DISPLAY 0.872340 (-852 1725);
PAINT GREEN (-852 1725);
DISPLAY INVISIBLE (-852 1725);
FORCEADD TAP..1
(-850 1675);
FORCEPROP 3 LASTPIN (-900 1675) SIG_NAME M_H_CPU0_SB_DQ<18>
J 0
(-890 1685);
DISPLAY 0.659574 (-890 1685);
PAINT MONO (-890 1685);
DISPLAY INVISIBLE (-890 1685);
FORCEPROP 1 LASTPIN (-900 1675) BN 18
J 0
(-912 1683);
DISPLAY 0.680851 (-912 1683);
PAINT GREEN (-912 1683);
FORCEPROP 2 LAST CDS_LIB standard
J 0
(-850 1675);
PAINT MONO (-850 1675);
DISPLAY INVISIBLE (-850 1675);
FORCEPROP 1 LAST BODY_TYPE PLUMBING
J 0
(-850 1725);
DISPLAY 0.872340 (-850 1725);
PAINT GREEN (-850 1725);
DISPLAY INVISIBLE (-850 1725);
FORCEPROP 1 LAST HDL_TAP TRUE
J 0
(-525 1550);
DISPLAY 0.872340 (-525 1550);
DISPLAY INVISIBLE (-525 1550);
FORCEPROP 1 LAST PATH I68
J 0
(-852 1675);
DISPLAY 0.872340 (-852 1675);
PAINT GREEN (-852 1675);
DISPLAY INVISIBLE (-852 1675);
FORCEADD TAP..1
(-850 1775);
FORCEPROP 3 LASTPIN (-900 1775) SIG_NAME M_H_CPU0_SB_DQ<20>
J 0
(-890 1785);
DISPLAY 0.659574 (-890 1785);
PAINT MONO (-890 1785);
DISPLAY INVISIBLE (-890 1785);
FORCEPROP 1 LASTPIN (-900 1775) BN 20
J 0
(-912 1783);
DISPLAY 0.680851 (-912 1783);
PAINT GREEN (-912 1783);
FORCEPROP 2 LAST CDS_LIB standard
J 0
(-850 1775);
PAINT MONO (-850 1775);
DISPLAY INVISIBLE (-850 1775);
FORCEPROP 1 LAST BODY_TYPE PLUMBING
J 0
(-850 1825);
DISPLAY 0.872340 (-850 1825);
PAINT GREEN (-850 1825);
DISPLAY INVISIBLE (-850 1825);
FORCEPROP 1 LAST HDL_TAP TRUE
J 0
(-525 1650);
DISPLAY 0.872340 (-525 1650);
DISPLAY INVISIBLE (-525 1650);
FORCEPROP 1 LAST PATH I69
J 0
(-852 1775);
DISPLAY 0.872340 (-852 1775);
PAINT GREEN (-852 1775);
DISPLAY INVISIBLE (-852 1775);
FORCEADD OFFPAGE..1
(-3350 1425);
FORCEPROP 2 LAST $XR7 97 
J 0
(-3722 1461);
DISPLAY 0.638298 (-3722 1461);
PAINT MONO (-3722 1461);
FORCEPROP 2 LAST $XR6 95 
J 0
(-3632 1461);
DISPLAY 0.638298 (-3632 1461);
PAINT MONO (-3632 1461);
FORCEPROP 2 LAST $XR5 94 
J 0
(-3812 1389);
DISPLAY 0.638298 (-3812 1389);
PAINT MONO (-3812 1389);
FORCEPROP 2 LAST $XR4 93 
J 0
(-3722 1389);
DISPLAY 0.638298 (-3722 1389);
PAINT MONO (-3722 1389);
FORCEPROP 2 LAST $XR3 92 
J 0
(-3632 1389);
DISPLAY 0.638298 (-3632 1389);
PAINT MONO (-3632 1389);
FORCEPROP 2 LAST $XR2 91 
J 0
(-3812 1425);
DISPLAY 0.638298 (-3812 1425);
PAINT MONO (-3812 1425);
FORCEPROP 2 LAST $XR1 90 
J 0
(-3722 1425);
DISPLAY 0.638298 (-3722 1425);
PAINT MONO (-3722 1425);
FORCEPROP 2 LAST $XR0 229 
J 0
(-3632 1425);
DISPLAY 0.638298 (-3632 1425);
PAINT MONO (-3632 1425);
FORCEPROP 2 LAST CDS_LIB standard
J 0
(-3350 1425);
PAINT MONO (-3350 1425);
DISPLAY INVISIBLE (-3350 1425);
FORCEPROP 1 LAST OFFPAGE TRUE
J 0
(-3025 1300);
DISPLAY 0.872340 (-3025 1300);
DISPLAY INVISIBLE (-3025 1300);
FORCEPROP 1 LAST COMMENT_BODY TRUE
J 0
(-3225 1325);
DISPLAY 0.872340 (-3225 1325);
PAINT GREEN (-3225 1325);
DISPLAY INVISIBLE (-3225 1325);
FORCEPROP 2 LAST PATH I7
J 0
(-3300 1500);
DISPLAY 1.021277 (-3300 1500);
DISPLAY INVISIBLE (-3300 1500);
FORCEADD TAP..1
(-850 1825);
FORCEPROP 3 LASTPIN (-900 1825) SIG_NAME M_H_CPU0_SB_DQ<21>
J 0
(-890 1835);
DISPLAY 0.659574 (-890 1835);
PAINT MONO (-890 1835);
DISPLAY INVISIBLE (-890 1835);
FORCEPROP 1 LASTPIN (-900 1825) BN 21
J 0
(-912 1833);
DISPLAY 0.680851 (-912 1833);
PAINT GREEN (-912 1833);
FORCEPROP 2 LAST CDS_LIB standard
J 0
(-850 1825);
PAINT MONO (-850 1825);
DISPLAY INVISIBLE (-850 1825);
FORCEPROP 1 LAST BODY_TYPE PLUMBING
J 0
(-850 1875);
DISPLAY 0.872340 (-850 1875);
PAINT GREEN (-850 1875);
DISPLAY INVISIBLE (-850 1875);
FORCEPROP 1 LAST HDL_TAP TRUE
J 0
(-525 1700);
DISPLAY 0.872340 (-525 1700);
DISPLAY INVISIBLE (-525 1700);
FORCEPROP 1 LAST PATH I70
J 0
(-852 1825);
DISPLAY 0.872340 (-852 1825);
PAINT GREEN (-852 1825);
DISPLAY INVISIBLE (-852 1825);
FORCEADD TAP..1
(-850 1875);
FORCEPROP 3 LASTPIN (-900 1875) SIG_NAME M_H_CPU0_SB_DQ<22>
J 0
(-890 1885);
DISPLAY 0.659574 (-890 1885);
PAINT MONO (-890 1885);
DISPLAY INVISIBLE (-890 1885);
FORCEPROP 1 LASTPIN (-900 1875) BN 22
J 0
(-912 1883);
DISPLAY 0.680851 (-912 1883);
PAINT GREEN (-912 1883);
FORCEPROP 2 LAST CDS_LIB standard
J 0
(-850 1875);
DISPLAY INVISIBLE (-850 1875);
FORCEPROP 1 LAST BODY_TYPE PLUMBING
J 0
(-850 1925);
DISPLAY 0.872340 (-850 1925);
PAINT GREEN (-850 1925);
DISPLAY INVISIBLE (-850 1925);
FORCEPROP 1 LAST HDL_TAP TRUE
J 0
(-525 1750);
DISPLAY 0.872340 (-525 1750);
DISPLAY INVISIBLE (-525 1750);
FORCEPROP 1 LAST PATH I71
J 0
(-852 1875);
DISPLAY 0.872340 (-852 1875);
PAINT GREEN (-852 1875);
DISPLAY INVISIBLE (-852 1875);
FORCEADD TAP..1
(-850 1925);
FORCEPROP 3 LASTPIN (-900 1925) SIG_NAME M_H_CPU0_SB_DQ<23>
J 0
(-890 1935);
DISPLAY 0.659574 (-890 1935);
PAINT MONO (-890 1935);
DISPLAY INVISIBLE (-890 1935);
FORCEPROP 1 LASTPIN (-900 1925) BN 23
J 0
(-912 1933);
DISPLAY 0.680851 (-912 1933);
PAINT GREEN (-912 1933);
FORCEPROP 2 LAST CDS_LIB standard
J 0
(-850 1925);
DISPLAY INVISIBLE (-850 1925);
FORCEPROP 1 LAST BODY_TYPE PLUMBING
J 0
(-850 1975);
DISPLAY 0.872340 (-850 1975);
PAINT GREEN (-850 1975);
DISPLAY INVISIBLE (-850 1975);
FORCEPROP 1 LAST HDL_TAP TRUE
J 0
(-525 1800);
DISPLAY 0.872340 (-525 1800);
DISPLAY INVISIBLE (-525 1800);
FORCEPROP 1 LAST PATH I72
J 0
(-852 1925);
DISPLAY 0.872340 (-852 1925);
PAINT GREEN (-852 1925);
DISPLAY INVISIBLE (-852 1925);
FORCEADD TAP..1
(-850 1975);
FORCEPROP 3 LASTPIN (-900 1975) SIG_NAME M_H_CPU0_SB_DQ<24>
J 0
(-890 1985);
DISPLAY 0.659574 (-890 1985);
PAINT MONO (-890 1985);
DISPLAY INVISIBLE (-890 1985);
FORCEPROP 1 LASTPIN (-900 1975) BN 24
J 0
(-912 1983);
DISPLAY 0.680851 (-912 1983);
PAINT GREEN (-912 1983);
FORCEPROP 2 LAST CDS_LIB standard
J 0
(-850 1975);
DISPLAY INVISIBLE (-850 1975);
FORCEPROP 1 LAST BODY_TYPE PLUMBING
J 0
(-850 2025);
DISPLAY 0.872340 (-850 2025);
PAINT GREEN (-850 2025);
DISPLAY INVISIBLE (-850 2025);
FORCEPROP 1 LAST HDL_TAP TRUE
J 0
(-525 1850);
DISPLAY 0.872340 (-525 1850);
DISPLAY INVISIBLE (-525 1850);
FORCEPROP 1 LAST PATH I73
J 0
(-852 1975);
DISPLAY 0.872340 (-852 1975);
PAINT GREEN (-852 1975);
DISPLAY INVISIBLE (-852 1975);
FORCEADD TAP..1
(-850 2025);
FORCEPROP 3 LASTPIN (-900 2025) SIG_NAME M_H_CPU0_SB_DQ<25>
J 0
(-890 2035);
DISPLAY 0.659574 (-890 2035);
PAINT MONO (-890 2035);
DISPLAY INVISIBLE (-890 2035);
FORCEPROP 1 LASTPIN (-900 2025) BN 25
J 0
(-912 2033);
DISPLAY 0.680851 (-912 2033);
PAINT GREEN (-912 2033);
FORCEPROP 2 LAST CDS_LIB standard
J 0
(-850 2025);
DISPLAY INVISIBLE (-850 2025);
FORCEPROP 1 LAST BODY_TYPE PLUMBING
J 0
(-850 2075);
DISPLAY 0.872340 (-850 2075);
PAINT GREEN (-850 2075);
DISPLAY INVISIBLE (-850 2075);
FORCEPROP 1 LAST HDL_TAP TRUE
J 0
(-525 1900);
DISPLAY 0.872340 (-525 1900);
DISPLAY INVISIBLE (-525 1900);
FORCEPROP 1 LAST PATH I74
J 0
(-852 2025);
DISPLAY 0.872340 (-852 2025);
PAINT GREEN (-852 2025);
DISPLAY INVISIBLE (-852 2025);
FORCEADD TAP..1
(-850 2075);
FORCEPROP 3 LASTPIN (-900 2075) SIG_NAME M_H_CPU0_SB_DQ<26>
J 0
(-890 2085);
DISPLAY 0.659574 (-890 2085);
PAINT MONO (-890 2085);
DISPLAY INVISIBLE (-890 2085);
FORCEPROP 1 LASTPIN (-900 2075) BN 26
J 0
(-912 2083);
DISPLAY 0.680851 (-912 2083);
PAINT GREEN (-912 2083);
FORCEPROP 2 LAST CDS_LIB standard
J 0
(-850 2075);
DISPLAY INVISIBLE (-850 2075);
FORCEPROP 1 LAST BODY_TYPE PLUMBING
J 0
(-850 2125);
DISPLAY 0.872340 (-850 2125);
PAINT GREEN (-850 2125);
DISPLAY INVISIBLE (-850 2125);
FORCEPROP 1 LAST HDL_TAP TRUE
J 0
(-525 1950);
DISPLAY 0.872340 (-525 1950);
DISPLAY INVISIBLE (-525 1950);
FORCEPROP 1 LAST PATH I75
J 0
(-852 2075);
DISPLAY 0.872340 (-852 2075);
PAINT GREEN (-852 2075);
DISPLAY INVISIBLE (-852 2075);
FORCEADD TAP..1
(-850 2125);
FORCEPROP 3 LASTPIN (-900 2125) SIG_NAME M_H_CPU0_SB_DQ<27>
J 0
(-890 2135);
DISPLAY 0.659574 (-890 2135);
PAINT MONO (-890 2135);
DISPLAY INVISIBLE (-890 2135);
FORCEPROP 1 LASTPIN (-900 2125) BN 27
J 0
(-912 2133);
DISPLAY 0.680851 (-912 2133);
PAINT GREEN (-912 2133);
FORCEPROP 2 LAST CDS_LIB standard
J 0
(-850 2125);
DISPLAY INVISIBLE (-850 2125);
FORCEPROP 1 LAST BODY_TYPE PLUMBING
J 0
(-850 2175);
DISPLAY 0.872340 (-850 2175);
PAINT GREEN (-850 2175);
DISPLAY INVISIBLE (-850 2175);
FORCEPROP 1 LAST HDL_TAP TRUE
J 0
(-525 2000);
DISPLAY 0.872340 (-525 2000);
DISPLAY INVISIBLE (-525 2000);
FORCEPROP 1 LAST PATH I76
J 0
(-852 2125);
DISPLAY 0.872340 (-852 2125);
PAINT GREEN (-852 2125);
DISPLAY INVISIBLE (-852 2125);
FORCEADD TAP..1
(-850 2175);
FORCEPROP 3 LASTPIN (-900 2175) SIG_NAME M_H_CPU0_SB_DQ<28>
J 0
(-890 2185);
DISPLAY 0.659574 (-890 2185);
PAINT MONO (-890 2185);
DISPLAY INVISIBLE (-890 2185);
FORCEPROP 1 LASTPIN (-900 2175) BN 28
J 0
(-912 2183);
DISPLAY 0.680851 (-912 2183);
PAINT GREEN (-912 2183);
FORCEPROP 2 LAST CDS_LIB standard
J 0
(-850 2175);
DISPLAY INVISIBLE (-850 2175);
FORCEPROP 1 LAST BODY_TYPE PLUMBING
J 0
(-850 2225);
DISPLAY 0.872340 (-850 2225);
PAINT GREEN (-850 2225);
DISPLAY INVISIBLE (-850 2225);
FORCEPROP 1 LAST HDL_TAP TRUE
J 0
(-525 2050);
DISPLAY 0.872340 (-525 2050);
DISPLAY INVISIBLE (-525 2050);
FORCEPROP 1 LAST PATH I77
J 0
(-852 2175);
DISPLAY 0.872340 (-852 2175);
PAINT GREEN (-852 2175);
DISPLAY INVISIBLE (-852 2175);
FORCEADD TAP..1
(-850 2225);
FORCEPROP 3 LASTPIN (-900 2225) SIG_NAME M_H_CPU0_SB_DQ<29>
J 0
(-890 2235);
DISPLAY 0.659574 (-890 2235);
PAINT MONO (-890 2235);
DISPLAY INVISIBLE (-890 2235);
FORCEPROP 1 LASTPIN (-900 2225) BN 29
J 0
(-912 2233);
DISPLAY 0.680851 (-912 2233);
PAINT GREEN (-912 2233);
FORCEPROP 2 LAST CDS_LIB standard
J 0
(-850 2225);
DISPLAY INVISIBLE (-850 2225);
FORCEPROP 1 LAST BODY_TYPE PLUMBING
J 0
(-850 2275);
DISPLAY 0.872340 (-850 2275);
PAINT GREEN (-850 2275);
DISPLAY INVISIBLE (-850 2275);
FORCEPROP 1 LAST HDL_TAP TRUE
J 0
(-525 2100);
DISPLAY 0.872340 (-525 2100);
DISPLAY INVISIBLE (-525 2100);
FORCEPROP 1 LAST PATH I78
J 0
(-852 2225);
DISPLAY 0.872340 (-852 2225);
PAINT GREEN (-852 2225);
DISPLAY INVISIBLE (-852 2225);
FORCEADD TAP..1
(-850 2275);
FORCEPROP 3 LASTPIN (-900 2275) SIG_NAME M_H_CPU0_SB_DQ<30>
J 0
(-890 2285);
DISPLAY 0.659574 (-890 2285);
PAINT MONO (-890 2285);
DISPLAY INVISIBLE (-890 2285);
FORCEPROP 1 LASTPIN (-900 2275) BN 30
J 0
(-912 2283);
DISPLAY 0.680851 (-912 2283);
PAINT GREEN (-912 2283);
FORCEPROP 2 LAST CDS_LIB standard
J 0
(-850 2275);
DISPLAY INVISIBLE (-850 2275);
FORCEPROP 1 LAST BODY_TYPE PLUMBING
J 0
(-850 2325);
DISPLAY 0.872340 (-850 2325);
PAINT GREEN (-850 2325);
DISPLAY INVISIBLE (-850 2325);
FORCEPROP 1 LAST HDL_TAP TRUE
J 0
(-525 2150);
DISPLAY 0.872340 (-525 2150);
DISPLAY INVISIBLE (-525 2150);
FORCEPROP 1 LAST PATH I79
J 0
(-852 2275);
DISPLAY 0.872340 (-852 2275);
PAINT GREEN (-852 2275);
DISPLAY INVISIBLE (-852 2275);
FORCEADD OFFPAGE..1
(-3425 1625);
FORCEPROP 2 LAST $XR1 97 
J 0
(-3736 1625);
DISPLAY 0.638298 (-3736 1625);
PAINT MONO (-3736 1625);
FORCEPROP 2 LAST $XR0 27 
J 0
(-3646 1625);
DISPLAY 0.638298 (-3646 1625);
PAINT MONO (-3646 1625);
FORCEPROP 2 LAST CDS_LIB standard
J 0
(-3425 1625);
PAINT MONO (-3425 1625);
DISPLAY INVISIBLE (-3425 1625);
FORCEPROP 1 LAST OFFPAGE TRUE
J 0
(-3100 1500);
DISPLAY 0.872340 (-3100 1500);
DISPLAY INVISIBLE (-3100 1500);
FORCEPROP 1 LAST COMMENT_BODY TRUE
J 0
(-3300 1525);
DISPLAY 0.872340 (-3300 1525);
PAINT GREEN (-3300 1525);
DISPLAY INVISIBLE (-3300 1525);
FORCEPROP 2 LAST PATH I8
J 0
(-3375 1700);
DISPLAY 1.021277 (-3375 1700);
DISPLAY INVISIBLE (-3375 1700);
FORCEADD TAP..1
(-850 2325);
FORCEPROP 3 LASTPIN (-900 2325) SIG_NAME M_H_CPU0_SB_DQ<31>
J 0
(-890 2335);
DISPLAY 0.659574 (-890 2335);
PAINT MONO (-890 2335);
DISPLAY INVISIBLE (-890 2335);
FORCEPROP 1 LASTPIN (-900 2325) BN 31
J 0
(-912 2333);
DISPLAY 0.680851 (-912 2333);
PAINT GREEN (-912 2333);
FORCEPROP 2 LAST CDS_LIB standard
J 0
(-850 2325);
DISPLAY INVISIBLE (-850 2325);
FORCEPROP 1 LAST BODY_TYPE PLUMBING
J 0
(-850 2375);
DISPLAY 0.872340 (-850 2375);
PAINT GREEN (-850 2375);
DISPLAY INVISIBLE (-850 2375);
FORCEPROP 1 LAST HDL_TAP TRUE
J 0
(-525 2200);
DISPLAY 0.872340 (-525 2200);
DISPLAY INVISIBLE (-525 2200);
FORCEPROP 1 LAST PATH I80
J 0
(-852 2325);
DISPLAY 0.872340 (-852 2325);
PAINT GREEN (-852 2325);
DISPLAY INVISIBLE (-852 2325);
FORCEADD TAP..1
(-850 2425);
FORCEPROP 3 LASTPIN (-900 2425) SIG_NAME M_H_CPU0_SA_DQ<0>
J 0
(-890 2435);
DISPLAY 0.659574 (-890 2435);
PAINT MONO (-890 2435);
DISPLAY INVISIBLE (-890 2435);
FORCEPROP 1 LASTPIN (-900 2425) BN 0
J 0
(-912 2433);
DISPLAY 0.680851 (-912 2433);
PAINT GREEN (-912 2433);
FORCEPROP 2 LAST CDS_LIB standard
J 0
(-850 2425);
PAINT MONO (-850 2425);
DISPLAY INVISIBLE (-850 2425);
FORCEPROP 1 LAST BODY_TYPE PLUMBING
J 0
(-850 2475);
DISPLAY 0.872340 (-850 2475);
PAINT GREEN (-850 2475);
DISPLAY INVISIBLE (-850 2475);
FORCEPROP 1 LAST HDL_TAP TRUE
J 0
(-525 2300);
DISPLAY 0.872340 (-525 2300);
DISPLAY INVISIBLE (-525 2300);
FORCEPROP 1 LAST PATH I81
J 0
(-852 2425);
DISPLAY 0.872340 (-852 2425);
PAINT GREEN (-852 2425);
DISPLAY INVISIBLE (-852 2425);
FORCEADD TAP..1
(-850 2525);
FORCEPROP 3 LASTPIN (-900 2525) SIG_NAME M_H_CPU0_SA_DQ<2>
J 0
(-890 2535);
DISPLAY 0.659574 (-890 2535);
PAINT MONO (-890 2535);
DISPLAY INVISIBLE (-890 2535);
FORCEPROP 1 LASTPIN (-900 2525) BN 2
J 0
(-912 2533);
DISPLAY 0.680851 (-912 2533);
PAINT GREEN (-912 2533);
FORCEPROP 2 LAST CDS_LIB standard
J 0
(-850 2525);
PAINT MONO (-850 2525);
DISPLAY INVISIBLE (-850 2525);
FORCEPROP 1 LAST BODY_TYPE PLUMBING
J 0
(-850 2575);
DISPLAY 0.872340 (-850 2575);
PAINT GREEN (-850 2575);
DISPLAY INVISIBLE (-850 2575);
FORCEPROP 1 LAST HDL_TAP TRUE
J 0
(-525 2400);
DISPLAY 0.872340 (-525 2400);
DISPLAY INVISIBLE (-525 2400);
FORCEPROP 1 LAST PATH I82
J 0
(-852 2525);
DISPLAY 0.872340 (-852 2525);
PAINT GREEN (-852 2525);
DISPLAY INVISIBLE (-852 2525);
FORCEADD TAP..1
(-850 2475);
FORCEPROP 3 LASTPIN (-900 2475) SIG_NAME M_H_CPU0_SA_DQ<1>
J 0
(-890 2485);
DISPLAY 0.659574 (-890 2485);
PAINT MONO (-890 2485);
DISPLAY INVISIBLE (-890 2485);
FORCEPROP 1 LASTPIN (-900 2475) BN 1
J 0
(-912 2483);
DISPLAY 0.680851 (-912 2483);
PAINT GREEN (-912 2483);
FORCEPROP 2 LAST CDS_LIB standard
J 0
(-850 2475);
PAINT MONO (-850 2475);
DISPLAY INVISIBLE (-850 2475);
FORCEPROP 1 LAST BODY_TYPE PLUMBING
J 0
(-850 2525);
DISPLAY 0.872340 (-850 2525);
PAINT GREEN (-850 2525);
DISPLAY INVISIBLE (-850 2525);
FORCEPROP 1 LAST HDL_TAP TRUE
J 0
(-525 2350);
DISPLAY 0.872340 (-525 2350);
DISPLAY INVISIBLE (-525 2350);
FORCEPROP 1 LAST PATH I83
J 0
(-852 2475);
DISPLAY 0.872340 (-852 2475);
PAINT GREEN (-852 2475);
DISPLAY INVISIBLE (-852 2475);
FORCEADD TAP..1
(-850 2575);
FORCEPROP 3 LASTPIN (-900 2575) SIG_NAME M_H_CPU0_SA_DQ<3>
J 0
(-890 2585);
DISPLAY 0.659574 (-890 2585);
PAINT MONO (-890 2585);
DISPLAY INVISIBLE (-890 2585);
FORCEPROP 1 LASTPIN (-900 2575) BN 3
J 0
(-912 2583);
DISPLAY 0.680851 (-912 2583);
PAINT GREEN (-912 2583);
FORCEPROP 2 LAST CDS_LIB standard
J 0
(-850 2575);
PAINT MONO (-850 2575);
DISPLAY INVISIBLE (-850 2575);
FORCEPROP 1 LAST BODY_TYPE PLUMBING
J 0
(-850 2625);
DISPLAY 0.872340 (-850 2625);
PAINT GREEN (-850 2625);
DISPLAY INVISIBLE (-850 2625);
FORCEPROP 1 LAST HDL_TAP TRUE
J 0
(-525 2450);
DISPLAY 0.872340 (-525 2450);
DISPLAY INVISIBLE (-525 2450);
FORCEPROP 1 LAST PATH I84
J 0
(-852 2575);
DISPLAY 0.872340 (-852 2575);
PAINT GREEN (-852 2575);
DISPLAY INVISIBLE (-852 2575);
FORCEADD TAP..1
(-850 2625);
FORCEPROP 3 LASTPIN (-900 2625) SIG_NAME M_H_CPU0_SA_DQ<4>
J 0
(-890 2635);
DISPLAY 0.659574 (-890 2635);
PAINT MONO (-890 2635);
DISPLAY INVISIBLE (-890 2635);
FORCEPROP 1 LASTPIN (-900 2625) BN 4
J 0
(-912 2633);
DISPLAY 0.680851 (-912 2633);
PAINT GREEN (-912 2633);
FORCEPROP 2 LAST CDS_LIB standard
J 0
(-850 2625);
PAINT MONO (-850 2625);
DISPLAY INVISIBLE (-850 2625);
FORCEPROP 1 LAST BODY_TYPE PLUMBING
J 0
(-850 2675);
DISPLAY 0.872340 (-850 2675);
PAINT GREEN (-850 2675);
DISPLAY INVISIBLE (-850 2675);
FORCEPROP 1 LAST HDL_TAP TRUE
J 0
(-525 2500);
DISPLAY 0.872340 (-525 2500);
DISPLAY INVISIBLE (-525 2500);
FORCEPROP 1 LAST PATH I85
J 0
(-852 2625);
DISPLAY 0.872340 (-852 2625);
PAINT GREEN (-852 2625);
DISPLAY INVISIBLE (-852 2625);
FORCEADD TAP..1
(-850 2675);
FORCEPROP 3 LASTPIN (-900 2675) SIG_NAME M_H_CPU0_SA_DQ<5>
J 0
(-890 2685);
DISPLAY 0.659574 (-890 2685);
PAINT MONO (-890 2685);
DISPLAY INVISIBLE (-890 2685);
FORCEPROP 1 LASTPIN (-900 2675) BN 5
J 0
(-912 2683);
DISPLAY 0.680851 (-912 2683);
PAINT GREEN (-912 2683);
FORCEPROP 2 LAST CDS_LIB standard
J 0
(-850 2675);
PAINT MONO (-850 2675);
DISPLAY INVISIBLE (-850 2675);
FORCEPROP 1 LAST BODY_TYPE PLUMBING
J 0
(-850 2725);
DISPLAY 0.872340 (-850 2725);
PAINT GREEN (-850 2725);
DISPLAY INVISIBLE (-850 2725);
FORCEPROP 1 LAST HDL_TAP TRUE
J 0
(-525 2550);
DISPLAY 0.872340 (-525 2550);
DISPLAY INVISIBLE (-525 2550);
FORCEPROP 1 LAST PATH I86
J 0
(-852 2675);
DISPLAY 0.872340 (-852 2675);
PAINT GREEN (-852 2675);
DISPLAY INVISIBLE (-852 2675);
FORCEADD TAP..1
(-850 2775);
FORCEPROP 3 LASTPIN (-900 2775) SIG_NAME M_H_CPU0_SA_DQ<7>
J 0
(-890 2785);
DISPLAY 0.659574 (-890 2785);
PAINT MONO (-890 2785);
DISPLAY INVISIBLE (-890 2785);
FORCEPROP 1 LASTPIN (-900 2775) BN 7
J 0
(-912 2783);
DISPLAY 0.680851 (-912 2783);
PAINT GREEN (-912 2783);
FORCEPROP 2 LAST CDS_LIB standard
J 0
(-850 2775);
PAINT MONO (-850 2775);
DISPLAY INVISIBLE (-850 2775);
FORCEPROP 1 LAST BODY_TYPE PLUMBING
J 0
(-850 2825);
DISPLAY 0.872340 (-850 2825);
PAINT GREEN (-850 2825);
DISPLAY INVISIBLE (-850 2825);
FORCEPROP 1 LAST HDL_TAP TRUE
J 0
(-525 2650);
DISPLAY 0.872340 (-525 2650);
DISPLAY INVISIBLE (-525 2650);
FORCEPROP 1 LAST PATH I87
J 0
(-852 2775);
DISPLAY 0.872340 (-852 2775);
PAINT GREEN (-852 2775);
DISPLAY INVISIBLE (-852 2775);
FORCEADD TAP..1
(-850 2725);
FORCEPROP 3 LASTPIN (-900 2725) SIG_NAME M_H_CPU0_SA_DQ<6>
J 0
(-890 2735);
DISPLAY 0.659574 (-890 2735);
PAINT MONO (-890 2735);
DISPLAY INVISIBLE (-890 2735);
FORCEPROP 1 LASTPIN (-900 2725) BN 6
J 0
(-912 2733);
DISPLAY 0.680851 (-912 2733);
PAINT GREEN (-912 2733);
FORCEPROP 2 LAST CDS_LIB standard
J 0
(-850 2725);
PAINT MONO (-850 2725);
DISPLAY INVISIBLE (-850 2725);
FORCEPROP 1 LAST BODY_TYPE PLUMBING
J 0
(-850 2775);
DISPLAY 0.872340 (-850 2775);
PAINT GREEN (-850 2775);
DISPLAY INVISIBLE (-850 2775);
FORCEPROP 1 LAST HDL_TAP TRUE
J 0
(-525 2600);
DISPLAY 0.872340 (-525 2600);
DISPLAY INVISIBLE (-525 2600);
FORCEPROP 1 LAST PATH I88
J 0
(-852 2725);
DISPLAY 0.872340 (-852 2725);
PAINT GREEN (-852 2725);
DISPLAY INVISIBLE (-852 2725);
FORCEADD TAP..1
(-850 2825);
FORCEPROP 3 LASTPIN (-900 2825) SIG_NAME M_H_CPU0_SA_DQ<8>
J 0
(-890 2835);
DISPLAY 0.659574 (-890 2835);
PAINT MONO (-890 2835);
DISPLAY INVISIBLE (-890 2835);
FORCEPROP 1 LASTPIN (-900 2825) BN 8
J 0
(-912 2833);
DISPLAY 0.680851 (-912 2833);
PAINT GREEN (-912 2833);
FORCEPROP 2 LAST CDS_LIB standard
J 0
(-850 2825);
PAINT MONO (-850 2825);
DISPLAY INVISIBLE (-850 2825);
FORCEPROP 1 LAST BODY_TYPE PLUMBING
J 0
(-850 2875);
DISPLAY 0.872340 (-850 2875);
PAINT GREEN (-850 2875);
DISPLAY INVISIBLE (-850 2875);
FORCEPROP 1 LAST HDL_TAP TRUE
J 0
(-525 2700);
DISPLAY 0.872340 (-525 2700);
DISPLAY INVISIBLE (-525 2700);
FORCEPROP 1 LAST PATH I89
J 0
(-852 2825);
DISPLAY 0.872340 (-852 2825);
PAINT GREEN (-852 2825);
DISPLAY INVISIBLE (-852 2825);
FORCEADD OFFPAGE..1
(-3350 1475);
FORCEPROP 2 LAST $XR0 96 
J 0
(-3811 1475);
DISPLAY 0.638298 (-3811 1475);
PAINT MONO (-3811 1475);
FORCEPROP 2 LAST CDS_LIB standard
J 0
(-3350 1475);
PAINT MONO (-3350 1475);
DISPLAY INVISIBLE (-3350 1475);
FORCEPROP 1 LAST OFFPAGE TRUE
J 0
(-3025 1350);
DISPLAY 0.872340 (-3025 1350);
DISPLAY INVISIBLE (-3025 1350);
FORCEPROP 1 LAST COMMENT_BODY TRUE
J 0
(-3225 1375);
DISPLAY 0.872340 (-3225 1375);
PAINT GREEN (-3225 1375);
DISPLAY INVISIBLE (-3225 1375);
FORCEPROP 2 LAST PATH I9
J 0
(-3300 1550);
DISPLAY 1.021277 (-3300 1550);
DISPLAY INVISIBLE (-3300 1550);
FORCEADD TAP..1
(-850 2875);
FORCEPROP 3 LASTPIN (-900 2875) SIG_NAME M_H_CPU0_SA_DQ<9>
J 0
(-890 2885);
DISPLAY 0.659574 (-890 2885);
PAINT MONO (-890 2885);
DISPLAY INVISIBLE (-890 2885);
FORCEPROP 1 LASTPIN (-900 2875) BN 9
J 0
(-912 2883);
DISPLAY 0.680851 (-912 2883);
PAINT GREEN (-912 2883);
FORCEPROP 2 LAST CDS_LIB standard
J 0
(-850 2875);
PAINT MONO (-850 2875);
DISPLAY INVISIBLE (-850 2875);
FORCEPROP 1 LAST BODY_TYPE PLUMBING
J 0
(-850 2925);
DISPLAY 0.872340 (-850 2925);
PAINT GREEN (-850 2925);
DISPLAY INVISIBLE (-850 2925);
FORCEPROP 1 LAST HDL_TAP TRUE
J 0
(-525 2750);
DISPLAY 0.872340 (-525 2750);
DISPLAY INVISIBLE (-525 2750);
FORCEPROP 1 LAST PATH I90
J 0
(-852 2875);
DISPLAY 0.872340 (-852 2875);
PAINT GREEN (-852 2875);
DISPLAY INVISIBLE (-852 2875);
FORCEADD TAP..1
(-850 2925);
FORCEPROP 3 LASTPIN (-900 2925) SIG_NAME M_H_CPU0_SA_DQ<10>
J 0
(-890 2935);
DISPLAY 0.659574 (-890 2935);
PAINT MONO (-890 2935);
DISPLAY INVISIBLE (-890 2935);
FORCEPROP 1 LASTPIN (-900 2925) BN 10
J 0
(-912 2933);
DISPLAY 0.680851 (-912 2933);
PAINT GREEN (-912 2933);
FORCEPROP 2 LAST CDS_LIB standard
J 0
(-850 2925);
PAINT MONO (-850 2925);
DISPLAY INVISIBLE (-850 2925);
FORCEPROP 1 LAST BODY_TYPE PLUMBING
J 0
(-850 2975);
DISPLAY 0.872340 (-850 2975);
PAINT GREEN (-850 2975);
DISPLAY INVISIBLE (-850 2975);
FORCEPROP 1 LAST HDL_TAP TRUE
J 0
(-525 2800);
DISPLAY 0.872340 (-525 2800);
DISPLAY INVISIBLE (-525 2800);
FORCEPROP 1 LAST PATH I91
J 0
(-852 2925);
DISPLAY 0.872340 (-852 2925);
PAINT GREEN (-852 2925);
DISPLAY INVISIBLE (-852 2925);
FORCEADD TAP..1
(-850 2975);
FORCEPROP 3 LASTPIN (-900 2975) SIG_NAME M_H_CPU0_SA_DQ<11>
J 0
(-890 2985);
DISPLAY 0.659574 (-890 2985);
PAINT MONO (-890 2985);
DISPLAY INVISIBLE (-890 2985);
FORCEPROP 1 LASTPIN (-900 2975) BN 11
J 0
(-912 2983);
DISPLAY 0.680851 (-912 2983);
PAINT GREEN (-912 2983);
FORCEPROP 2 LAST CDS_LIB standard
J 0
(-850 2975);
PAINT MONO (-850 2975);
DISPLAY INVISIBLE (-850 2975);
FORCEPROP 1 LAST BODY_TYPE PLUMBING
J 0
(-850 3025);
DISPLAY 0.872340 (-850 3025);
PAINT GREEN (-850 3025);
DISPLAY INVISIBLE (-850 3025);
FORCEPROP 1 LAST HDL_TAP TRUE
J 0
(-525 2850);
DISPLAY 0.872340 (-525 2850);
DISPLAY INVISIBLE (-525 2850);
FORCEPROP 1 LAST PATH I92
J 0
(-852 2975);
DISPLAY 0.872340 (-852 2975);
PAINT GREEN (-852 2975);
DISPLAY INVISIBLE (-852 2975);
FORCEADD TAP..1
(-850 3025);
FORCEPROP 3 LASTPIN (-900 3025) SIG_NAME M_H_CPU0_SA_DQ<12>
J 0
(-890 3035);
DISPLAY 0.659574 (-890 3035);
PAINT MONO (-890 3035);
DISPLAY INVISIBLE (-890 3035);
FORCEPROP 1 LASTPIN (-900 3025) BN 12
J 0
(-912 3033);
DISPLAY 0.680851 (-912 3033);
PAINT GREEN (-912 3033);
FORCEPROP 2 LAST CDS_LIB standard
J 0
(-850 3025);
PAINT MONO (-850 3025);
DISPLAY INVISIBLE (-850 3025);
FORCEPROP 1 LAST BODY_TYPE PLUMBING
J 0
(-850 3075);
DISPLAY 0.872340 (-850 3075);
PAINT GREEN (-850 3075);
DISPLAY INVISIBLE (-850 3075);
FORCEPROP 1 LAST HDL_TAP TRUE
J 0
(-525 2900);
DISPLAY 0.872340 (-525 2900);
DISPLAY INVISIBLE (-525 2900);
FORCEPROP 1 LAST PATH I93
J 0
(-852 3025);
DISPLAY 0.872340 (-852 3025);
PAINT GREEN (-852 3025);
DISPLAY INVISIBLE (-852 3025);
FORCEADD TAP..1
(-850 3075);
FORCEPROP 3 LASTPIN (-900 3075) SIG_NAME M_H_CPU0_SA_DQ<13>
J 0
(-890 3085);
DISPLAY 0.659574 (-890 3085);
PAINT MONO (-890 3085);
DISPLAY INVISIBLE (-890 3085);
FORCEPROP 1 LASTPIN (-900 3075) BN 13
J 0
(-912 3083);
DISPLAY 0.680851 (-912 3083);
PAINT GREEN (-912 3083);
FORCEPROP 2 LAST CDS_LIB standard
J 0
(-850 3075);
PAINT MONO (-850 3075);
DISPLAY INVISIBLE (-850 3075);
FORCEPROP 1 LAST BODY_TYPE PLUMBING
J 0
(-850 3125);
DISPLAY 0.872340 (-850 3125);
PAINT GREEN (-850 3125);
DISPLAY INVISIBLE (-850 3125);
FORCEPROP 1 LAST HDL_TAP TRUE
J 0
(-525 2950);
DISPLAY 0.872340 (-525 2950);
DISPLAY INVISIBLE (-525 2950);
FORCEPROP 1 LAST PATH I94
J 0
(-852 3075);
DISPLAY 0.872340 (-852 3075);
PAINT GREEN (-852 3075);
DISPLAY INVISIBLE (-852 3075);
FORCEADD TAP..1
(-850 3125);
FORCEPROP 3 LASTPIN (-900 3125) SIG_NAME M_H_CPU0_SA_DQ<14>
J 0
(-890 3135);
DISPLAY 0.659574 (-890 3135);
PAINT MONO (-890 3135);
DISPLAY INVISIBLE (-890 3135);
FORCEPROP 1 LASTPIN (-900 3125) BN 14
J 0
(-912 3133);
DISPLAY 0.680851 (-912 3133);
PAINT GREEN (-912 3133);
FORCEPROP 2 LAST CDS_LIB standard
J 0
(-850 3125);
PAINT MONO (-850 3125);
DISPLAY INVISIBLE (-850 3125);
FORCEPROP 1 LAST BODY_TYPE PLUMBING
J 0
(-850 3175);
DISPLAY 0.872340 (-850 3175);
PAINT GREEN (-850 3175);
DISPLAY INVISIBLE (-850 3175);
FORCEPROP 1 LAST HDL_TAP TRUE
J 0
(-525 3000);
DISPLAY 0.872340 (-525 3000);
DISPLAY INVISIBLE (-525 3000);
FORCEPROP 1 LAST PATH I95
J 0
(-852 3125);
DISPLAY 0.872340 (-852 3125);
PAINT GREEN (-852 3125);
DISPLAY INVISIBLE (-852 3125);
FORCEADD TAP..1
(-850 3175);
FORCEPROP 3 LASTPIN (-900 3175) SIG_NAME M_H_CPU0_SA_DQ<15>
J 0
(-890 3185);
DISPLAY 0.659574 (-890 3185);
PAINT MONO (-890 3185);
DISPLAY INVISIBLE (-890 3185);
FORCEPROP 1 LASTPIN (-900 3175) BN 15
J 0
(-912 3183);
DISPLAY 0.680851 (-912 3183);
PAINT GREEN (-912 3183);
FORCEPROP 2 LAST CDS_LIB standard
J 0
(-850 3175);
PAINT MONO (-850 3175);
DISPLAY INVISIBLE (-850 3175);
FORCEPROP 1 LAST BODY_TYPE PLUMBING
J 0
(-850 3225);
DISPLAY 0.872340 (-850 3225);
PAINT GREEN (-850 3225);
DISPLAY INVISIBLE (-850 3225);
FORCEPROP 1 LAST HDL_TAP TRUE
J 0
(-525 3050);
DISPLAY 0.872340 (-525 3050);
DISPLAY INVISIBLE (-525 3050);
FORCEPROP 1 LAST PATH I96
J 0
(-852 3175);
DISPLAY 0.872340 (-852 3175);
PAINT GREEN (-852 3175);
DISPLAY INVISIBLE (-852 3175);
FORCEADD TAP..1
(-850 3225);
FORCEPROP 3 LASTPIN (-900 3225) SIG_NAME M_H_CPU0_SA_DQ<16>
J 0
(-890 3235);
DISPLAY 0.659574 (-890 3235);
PAINT MONO (-890 3235);
DISPLAY INVISIBLE (-890 3235);
FORCEPROP 1 LASTPIN (-900 3225) BN 16
J 0
(-912 3233);
DISPLAY 0.680851 (-912 3233);
PAINT GREEN (-912 3233);
FORCEPROP 2 LAST CDS_LIB standard
J 0
(-850 3225);
PAINT MONO (-850 3225);
DISPLAY INVISIBLE (-850 3225);
FORCEPROP 1 LAST BODY_TYPE PLUMBING
J 0
(-850 3275);
DISPLAY 0.872340 (-850 3275);
PAINT GREEN (-850 3275);
DISPLAY INVISIBLE (-850 3275);
FORCEPROP 1 LAST HDL_TAP TRUE
J 0
(-525 3100);
DISPLAY 0.872340 (-525 3100);
DISPLAY INVISIBLE (-525 3100);
FORCEPROP 1 LAST PATH I97
J 0
(-852 3225);
DISPLAY 0.872340 (-852 3225);
PAINT GREEN (-852 3225);
DISPLAY INVISIBLE (-852 3225);
FORCEADD TAP..1
(-850 3275);
FORCEPROP 3 LASTPIN (-900 3275) SIG_NAME M_H_CPU0_SA_DQ<17>
J 0
(-890 3285);
DISPLAY 0.659574 (-890 3285);
PAINT MONO (-890 3285);
DISPLAY INVISIBLE (-890 3285);
FORCEPROP 1 LASTPIN (-900 3275) BN 17
J 0
(-912 3283);
DISPLAY 0.680851 (-912 3283);
PAINT GREEN (-912 3283);
FORCEPROP 2 LAST CDS_LIB standard
J 0
(-850 3275);
PAINT MONO (-850 3275);
DISPLAY INVISIBLE (-850 3275);
FORCEPROP 1 LAST BODY_TYPE PLUMBING
J 0
(-850 3325);
DISPLAY 0.872340 (-850 3325);
PAINT GREEN (-850 3325);
DISPLAY INVISIBLE (-850 3325);
FORCEPROP 1 LAST HDL_TAP TRUE
J 0
(-525 3150);
DISPLAY 0.872340 (-525 3150);
DISPLAY INVISIBLE (-525 3150);
FORCEPROP 1 LAST PATH I98
J 0
(-852 3275);
DISPLAY 0.872340 (-852 3275);
PAINT GREEN (-852 3275);
DISPLAY INVISIBLE (-852 3275);
FORCEADD TAP..1
(-850 3325);
FORCEPROP 3 LASTPIN (-900 3325) SIG_NAME M_H_CPU0_SA_DQ<18>
J 0
(-890 3335);
DISPLAY 0.659574 (-890 3335);
PAINT MONO (-890 3335);
DISPLAY INVISIBLE (-890 3335);
FORCEPROP 1 LASTPIN (-900 3325) BN 18
J 0
(-912 3333);
DISPLAY 0.680851 (-912 3333);
PAINT GREEN (-912 3333);
FORCEPROP 2 LAST CDS_LIB standard
J 0
(-850 3325);
PAINT MONO (-850 3325);
DISPLAY INVISIBLE (-850 3325);
FORCEPROP 1 LAST BODY_TYPE PLUMBING
J 0
(-850 3375);
DISPLAY 0.872340 (-850 3375);
PAINT GREEN (-850 3375);
DISPLAY INVISIBLE (-850 3375);
FORCEPROP 1 LAST HDL_TAP TRUE
J 0
(-525 3200);
DISPLAY 0.872340 (-525 3200);
DISPLAY INVISIBLE (-525 3200);
FORCEPROP 1 LAST PATH I99
J 0
(-852 3325);
DISPLAY 0.872340 (-852 3325);
PAINT GREEN (-852 3325);
DISPLAY INVISIBLE (-852 3325);
FORCEADD CAD_NOTE..1
(1000 -475);
FORCEPROP 0 LAST S1 PLACE THE BYPASS CAPS CLOSE TO DIMM
J 0
(875 -600);
DISPLAY 1.021277 (875 -600);
PAINT WHITE (875 -600);
FORCEPROP 2 LAST CDS_LIB logical_power
J 0
(1000 -475);
PAINT MONO (1000 -475);
DISPLAY INVISIBLE (1000 -475);
FORCEPROP 1 LAST COMMENT_BODY TRUE
J 0
(1025 -375);
DISPLAY 0.978723 (1025 -375);
DISPLAY INVISIBLE (1025 -375);
FORCEADD QUANTA_TITLE_BLOCK_C..1
(5475 -1775);
FORCEPROP 0 LAST CDS_CON_LAST_MODIFIED Fri Aug 25 14:01:16 2023
J 0
(3590 -1760);
PAINT MONO (3590 -1760);
DISPLAY INVISIBLE (3590 -1760);
FORCEPROP 1 LAST CUSTOM_TXT_CDS <CON_LAST_MODIFIED>
J 0
(3590 -1760);
DISPLAY 0.978723 (3590 -1760);
FORCEPROP 2 LAST CUSTOM_TXT_CDS <XR_PAGE_TITLE>
J 0
(-2415 3475);
DISPLAY 0.638298 (-2415 3475);
PAINT PINK (-2415 3475);
DISPLAY INVISIBLE (-2415 3475);
FORCEPROP 2 LAST CUSTOM_TXT_CDS <CON_PAGE_NUM> OF <CON_TOTAL_PAGES>
J 0
(5029 -1757);
DISPLAY 0.978723 (5029 -1757);
FORCEPROP 2 LAST CUSTOM_TXT_CDS <Q_REV>
J 0
(5291 -1672);
DISPLAY 1.212766 (5291 -1672);
FORCEPROP 2 LAST CUSTOM_TXT_CDS <Q_NUMBER>
J 0
(4072 -1672);
DISPLAY 1.212766 (4072 -1672);
FORCEPROP 2 LAST CUSTOM_TXT_CDS <Q_PROJ>
J 0
(3093 -1673);
DISPLAY 1.212766 (3093 -1673);
FORCEPROP 2 LAST CUSTOM_TXT_CDS <NAME_1>
J 0
(2300 -1600);
FORCEPROP 2 LAST CUSTOM_TXT_CDS <NAME_2>
J 0
(2300 -1725);
FORCEPROP 1 LAST Q_TITLE DDR5 - CPU0 CHH DIMM1(YELLOW)
J 0
(-3891 -1749);
DISPLAY 2.446809 (-3891 -1749);
PAINT GREEN (-3891 -1749);
FORCEPROP 1 LAST Q_DEPT 
J 1
(1712 -1726);
DISPLAY 1.957447 (1712 -1726);
PAINT GREEN (1712 -1726);
FORCEPROP 1 LAST COMMENT_BODY TRUE
J 0
(5487 -1788);
DISPLAY 0.978723 (5487 -1788);
PAINT GREEN (5487 -1788);
DISPLAY INVISIBLE (5487 -1788);
FORCEPROP 2 LAST CDS_XR_PAGE_TITLE CR-96 : @S9S_MB_2U_LIB.S9S_MB_2U(SCH_1):PAGE96
J 0
(-2415 3475);
DISPLAY 0.638298 (-2415 3475);
PAINT PINK (-2415 3475);
DISPLAY INVISIBLE (-2415 3475);
FORCEPROP 2 LAST CDS_LIB pure_quanta
J 0
(5475 -1775);
PAINT MONO (5475 -1775);
DISPLAY INVISIBLE (5475 -1775);
FORCEPROP 1 LAST CDS_LMAN_SYM_OUTLINE -9475,6775,100,-125
J 0
(5475 -1775);
DISPLAY 0.468085 (5475 -1775);
PAINT GREEN (5475 -1775);
DISPLAY INVISIBLE (5475 -1775);
FORCEPROP 2 LAST PAGE_BORDER TRUE
J 0
(-2415 3475);
DISPLAY 0.638298 (-2415 3475);
PAINT PINK (-2415 3475);
DISPLAY INVISIBLE (-2415 3475);
WIRE 17 -1 (-2550 2550)(-2550 2600);
WIRE 17 -1 (-2550 2500)(-2550 2550);
WIRE 17 -1 (-3375 2600)(-2550 2600);
FORCEPROP 2 LAST SIG_NAME M_H_CPU0_SA_CB<7:0>
J 0
(-3285 2610);
DISPLAY 0.680851 (-3285 2610);
PAINT WHITE (-3285 2610);
WIRE 17 -1 (-2550 2450)(-2550 2500);
WIRE 17 -1 (-2550 2400)(-2550 2450);
WIRE 17 -1 (-2550 2350)(-2550 2400);
WIRE 17 -1 (-2550 2300)(-2550 2350);
WIRE 17 -1 (-2550 2250)(-2550 2300);
WIRE 17 -1 (-2550 2100)(-2550 2150);
WIRE 17 -1 (-2550 2050)(-2550 2100);
WIRE 17 -1 (-3375 2150)(-2550 2150);
FORCEPROP 2 LAST SIG_NAME M_H_CPU0_SB_CB<7:0>
J 0
(-3285 2160);
DISPLAY 0.680851 (-3285 2160);
PAINT WHITE (-3285 2160);
WIRE 17 -1 (-2550 3700)(-2550 3750);
WIRE 17 -1 (-2550 3750)(-2550 3800);
WIRE 17 -1 (-2550 3800)(-2550 3850);
WIRE 17 -1 (-2550 3850)(-2550 3900);
WIRE 17 -1 (-2550 3900)(-2550 3950);
WIRE 17 -1 (-2550 3950)(-2550 4000);
WIRE 17 -1 (-3375 4000)(-2550 4000);
FORCEPROP 2 LAST SIG_NAME M_H_CPU0_SA_CA<6:0>
J 0
(-3285 4010);
DISPLAY 0.680851 (-3285 4010);
PAINT WHITE (-3285 4010);
WIRE 17 -1 (-2550 3300)(-2550 3350);
WIRE 17 -1 (-2550 3350)(-2550 3400);
WIRE 17 -1 (-2550 3400)(-2550 3450);
WIRE 17 -1 (-2550 3450)(-2550 3500);
WIRE 17 -1 (-2550 3500)(-2550 3550);
WIRE 17 -1 (-2550 3550)(-2550 3600);
WIRE 17 -1 (-3375 3600)(-2550 3600);
FORCEPROP 2 LAST SIG_NAME M_H_CPU0_SB_CA<6:0>
J 0
(-3285 3610);
DISPLAY 0.680851 (-3285 3610);
PAINT WHITE (-3285 3610);
WIRE 17 -1 (-2550 2000)(-2550 2050);
WIRE 17 -1 (-2550 1950)(-2550 2000);
WIRE 17 -1 (-2550 1900)(-2550 1950);
WIRE 17 -1 (-2550 1850)(-2550 1900);
WIRE 17 -1 (-2550 1800)(-2550 1850);
WIRE 17 -1 (-800 3900)(-800 3950);
WIRE 17 -1 (-800 3850)(-800 3900);
WIRE 17 -1 (-800 3950)(-800 4000);
WIRE 17 -1 (-800 4000)(-75 4000);
FORCEPROP 2 LAST SIG_NAME M_H_CPU0_SA_DQ<31:0>
J 0
(-735 4010);
DISPLAY 0.680851 (-735 4010);
PAINT WHITE (-735 4010);
WIRE 17 -1 (-800 3800)(-800 3850);
WIRE 17 -1 (-800 3750)(-800 3800);
WIRE 17 -1 (-800 3700)(-800 3750);
WIRE 17 -1 (-800 3650)(-800 3700);
WIRE 17 -1 (-800 3600)(-800 3650);
WIRE 17 -1 (-800 3550)(-800 3600);
WIRE 17 -1 (-800 3500)(-800 3550);
WIRE 17 -1 (-800 3450)(-800 3500);
WIRE 17 -1 (-800 3400)(-800 3450);
WIRE 17 -1 (-800 3350)(-800 3400);
WIRE 17 -1 (-800 3300)(-800 3350);
WIRE 17 -1 (-800 3250)(-800 3300);
WIRE 17 -1 (-800 3200)(-800 3250);
WIRE 17 -1 (-800 3150)(-800 3200);
WIRE 17 -1 (-800 3100)(-800 3150);
WIRE 17 -1 (-800 3050)(-800 3100);
WIRE 17 -1 (-800 3000)(-800 3050);
WIRE 17 -1 (-800 2950)(-800 3000);
WIRE 17 -1 (-800 2900)(-800 2950);
WIRE 17 -1 (-800 2850)(-800 2900);
WIRE 17 -1 (-800 2800)(-800 2850);
WIRE 17 -1 (-800 2750)(-800 2800);
WIRE 17 -1 (-800 2700)(-800 2750);
WIRE 17 -1 (-800 2650)(-800 2700);
WIRE 17 -1 (-800 2600)(-800 2650);
WIRE 17 -1 (-800 2550)(-800 2600);
WIRE 17 -1 (-800 2500)(-800 2550);
WIRE 17 -1 (-800 2450)(-800 2500);
WIRE 17 -1 (-800 2300)(-800 2350);
WIRE 17 -1 (-800 2250)(-800 2300);
WIRE 17 -1 (-800 2350)(-75 2350);
FORCEPROP 2 LAST SIG_NAME M_H_CPU0_SB_DQ<31:0>
J 0
(-735 2360);
DISPLAY 0.680851 (-735 2360);
PAINT WHITE (-735 2360);
WIRE 17 -1 (-800 2200)(-800 2250);
WIRE 17 -1 (-800 2150)(-800 2200);
WIRE 17 -1 (-800 2100)(-800 2150);
WIRE 17 -1 (-800 2050)(-800 2100);
WIRE 17 -1 (-800 2000)(-800 2050);
WIRE 17 -1 (-800 1950)(-800 2000);
WIRE 17 -1 (-800 1900)(-800 1950);
WIRE 17 -1 (-800 1850)(-800 1900);
WIRE 17 -1 (-800 1800)(-800 1850);
WIRE 17 -1 (-800 1750)(-800 1800);
WIRE 17 -1 (-800 1700)(-800 1750);
WIRE 17 -1 (-800 1650)(-800 1700);
WIRE 17 -1 (-800 1600)(-800 1650);
WIRE 17 -1 (-800 1550)(-800 1600);
WIRE 17 -1 (-800 1500)(-800 1550);
WIRE 17 -1 (-800 1450)(-800 1500);
WIRE 17 -1 (-800 1400)(-800 1450);
WIRE 17 -1 (-800 1350)(-800 1400);
WIRE 17 -1 (-800 1300)(-800 1350);
WIRE 17 -1 (-800 1250)(-800 1300);
WIRE 17 -1 (-800 1200)(-800 1250);
WIRE 17 -1 (-800 1150)(-800 1200);
WIRE 17 -1 (-800 1100)(-800 1150);
WIRE 17 -1 (-800 1050)(-800 1100);
WIRE 17 -1 (-800 1000)(-800 1050);
WIRE 17 -1 (-800 950)(-800 1000);
WIRE 17 -1 (-800 900)(-800 950);
WIRE 17 -1 (-800 850)(-800 900);
WIRE 17 -1 (-800 800)(-800 850);
WIRE 17 -1 (1950 2050)(1950 2150);
WIRE 17 -1 (1950 2150)(1950 2250);
WIRE 17 -1 (1950 2250)(1950 2350);
WIRE 17 -1 (1950 2450)(1950 2350);
WIRE 17 -1 (1950 2450)(1950 2550);
WIRE 17 -1 (1950 2550)(1950 2650);
WIRE 17 -1 (1950 2650)(1950 2750);
WIRE 17 -1 (1950 2750)(1950 2850);
WIRE 17 -1 (1950 2850)(1950 2950);
WIRE 17 -1 (1950 2950)(2975 2950);
FORCEPROP 2 LAST SIG_NAME M_H_CPU0_SB_DQS_DP<9:0>
J 0
(2190 2960);
DISPLAY 0.680851 (2190 2960);
PAINT WHITE (2190 2960);
WIRE 17 -1 (1950 3100)(1950 3200);
WIRE 17 -1 (1950 3200)(1950 3300);
WIRE 17 -1 (1950 3300)(1950 3400);
WIRE 17 -1 (1950 3500)(1950 3400);
WIRE 17 -1 (1950 3500)(1950 3600);
WIRE 17 -1 (1950 3600)(1950 3700);
WIRE 17 -1 (1950 3700)(1950 3800);
WIRE 17 -1 (1950 3800)(1950 3900);
WIRE 17 -1 (1950 3900)(1950 4000);
WIRE 17 -1 (1950 4000)(2975 4000);
FORCEPROP 2 LAST SIG_NAME M_H_CPU0_SA_DQS_DP<9:0>
J 0
(2190 4010);
DISPLAY 0.680851 (2190 4010);
PAINT WHITE (2190 4010);
WIRE 17 -1 (2125 2000)(2125 2100);
WIRE 17 -1 (2125 2100)(2125 2200);
WIRE 17 -1 (2125 2200)(2125 2300);
WIRE 17 -1 (2125 2400)(2125 2300);
WIRE 17 -1 (2125 2400)(2125 2500);
WIRE 17 -1 (2125 2500)(2125 2600);
WIRE 17 -1 (2125 2600)(2125 2700);
WIRE 17 -1 (2125 2700)(2125 2800);
WIRE 17 -1 (2125 2800)(2125 2900);
WIRE 17 -1 (2125 2900)(2975 2900);
FORCEPROP 2 LAST SIG_NAME M_H_CPU0_SB_DQS_DN<9:0>
J 0
(2190 2910);
DISPLAY 0.680851 (2190 2910);
PAINT WHITE (2190 2910);
WIRE 17 -1 (2125 3050)(2125 3150);
WIRE 17 -1 (2125 3150)(2125 3250);
WIRE 17 -1 (2125 3250)(2125 3350);
WIRE 17 -1 (2125 3450)(2125 3350);
WIRE 17 -1 (2125 3450)(2125 3550);
WIRE 17 -1 (2125 3550)(2125 3650);
WIRE 17 -1 (2125 3650)(2125 3750);
WIRE 17 -1 (2125 3750)(2125 3850);
WIRE 17 -1 (2125 3850)(2125 3950);
WIRE 17 -1 (2125 3950)(2975 3950);
FORCEPROP 2 LAST SIG_NAME M_H_CPU0_SA_DQS_DN<9:0>
J 0
(2190 3960);
DISPLAY 0.680851 (2190 3960);
PAINT WHITE (2190 3960);
WIRE 16 -1 (-3325 1800)(-3325 1525);
WIRE 16 -1 (3575 4475)(3575 3975);
WIRE 16 -1 (1875 375)(1875 325);
WIRE 16 -1 (875 200)(875 375);
WIRE 16 -1 (5275 625)(5275 325);
WIRE 16 -1 (5275 675)(5275 625);
WIRE 16 -1 (5025 625)(5275 625);
WIRE 16 -1 (3575 325)(3575 725);
WIRE 16 -1 (2500 -225)(2500 -150);
WIRE 16 -1 (875 0)(875 -225);
WIRE 16 -1 (-2275 -350)(-2275 -275);
WIRE 16 3135 (525 600)(525 -700);
WIRE 16 3135 (3125 600)(525 600);
WIRE 16 3135 (525 -700)(3125 -700);
WIRE 16 3135 (3125 -700)(3125 600);
WIRE 16 -1 (-1075 2225)(-900 2225);
WIRE 16 -1 (-2275 2675)(-3375 2675);
FORCEPROP 2 LAST SIG_NAME M_H_CPU0_CLK_DN<0>
J 0
(-3287 2684);
DISPLAY 0.680851 (-3287 2684);
PAINT WHITE (-3287 2684);
WIRE 16 -1 (-3325 1525)(-2275 1525);
WIRE 16 -1 (-2275 1625)(-3375 1625);
FORCEPROP 2 LAST SIG_NAME M_H_CPU0_ALERT_N
J 0
(-3287 1634);
DISPLAY 0.680851 (-3287 1634);
PAINT WHITE (-3287 1634);
WIRE 16 -1 (-2275 1475)(-3300 1475);
FORCEPROP 2 LAST SIG_NAME PD_CHH_CPU0_DIMM1_SAA
J 0
(-3285 1485);
DISPLAY 0.680851 (-3285 1485);
PAINT WHITE (-3285 1485);
WIRE 16 -1 (-2275 1425)(-3300 1425);
FORCEPROP 2 LAST SIG_NAME I3C_SPD_DDREFGH_CPU0_LVC1_SDA
J 0
(-3285 1435);
DISPLAY 0.680851 (-3285 1435);
PAINT WHITE (-3285 1435);
WIRE 16 -1 (-3750 1250)(-3550 1250);
WIRE 16 -1 (-3750 1250)(-3750 1375);
WIRE 16 -1 (-2275 1375)(-3750 1375);
FORCEPROP 2 LAST SIG_NAME I3C_SPD_DDREFGH_CPU0_LVC1_SCL_R7
J 0
(-3335 1385);
DISPLAY 0.680851 (-3335 1385);
PAINT WHITE (-3335 1385);
WIRE 16 -1 (-2675 1725)(-3375 1725);
FORCEPROP 2 LAST SIG_NAME RST_M_GH_CPU0_FPGA_N
J 0
(-3287 1734);
DISPLAY 0.680851 (-3287 1734);
PAINT WHITE (-3287 1734);
WIRE 16 -1 (-2675 1725)(-2675 1675);
WIRE 16 -1 (-2675 1675)(-2275 1675);
WIRE 16 -1 (-2175 1200)(-2225 1200);
WIRE 16 -1 (-3350 1250)(-2175 1250);
FORCEPROP 2 LAST SIG_NAME I3C_SPD_DDREFGH_CPU0_LVC1_SCL
J 0
(-3185 1260);
DISPLAY 0.680851 (-3185 1260);
PAINT WHITE (-3185 1260);
WIRE 16 -1 (-2175 1250)(-2175 1200);
WIRE 16 -1 (-2275 1125)(-3375 1125);
FORCEPROP 2 LAST SIG_NAME PWRGD_CHH_CPU0_DIMM1
J 0
(-3287 1134);
DISPLAY 0.680851 (-3287 1134);
PAINT WHITE (-3287 1134);
WIRE 16 -1 (-2275 1025)(-3375 1025);
FORCEPROP 2 LAST SIG_NAME TP_CHH_CPU0_DIMM1_FRU_6
J 0
(-3287 1034);
DISPLAY 0.680851 (-3287 1034);
PAINT WHITE (-3287 1034);
WIRE 16 -1 (-2450 1825)(-2275 1825);
WIRE 16 -1 (1750 3925)(2025 3925);
WIRE 16 -1 (1750 3825)(2025 3825);
WIRE 16 -1 (2025 3725)(1750 3725);
WIRE 16 -1 (1750 3625)(2025 3625);
WIRE 16 -1 (1750 3525)(2025 3525);
WIRE 16 -1 (1750 3425)(2025 3425);
WIRE 16 -1 (1750 3225)(2025 3225);
WIRE 16 -1 (1750 3325)(2025 3325);
WIRE 16 -1 (1750 3125)(2025 3125);
WIRE 16 -1 (1750 3025)(2025 3025);
WIRE 16 -1 (1750 2875)(2025 2875);
WIRE 16 -1 (1750 2775)(2025 2775);
WIRE 16 -1 (1750 2575)(2025 2575);
WIRE 16 -1 (1750 2675)(2025 2675);
WIRE 16 -1 (1750 2475)(2025 2475);
WIRE 16 -1 (1750 2375)(2025 2375);
WIRE 16 -1 (1750 2275)(2025 2275);
WIRE 16 -1 (1750 2075)(2025 2075);
WIRE 16 -1 (1750 2175)(2025 2175);
WIRE 16 -1 (1750 1975)(2025 1975);
WIRE 16 -1 (1750 3975)(1850 3975);
WIRE 16 -1 (1750 3875)(1850 3875);
WIRE 16 -1 (1750 3775)(1850 3775);
WIRE 16 -1 (1750 3675)(1850 3675);
WIRE 16 -1 (1750 3575)(1850 3575);
WIRE 16 -1 (1750 3475)(1850 3475);
WIRE 16 -1 (1750 3375)(1850 3375);
WIRE 16 -1 (1750 3275)(1850 3275);
WIRE 16 -1 (1750 3175)(1850 3175);
WIRE 16 -1 (1750 3075)(1850 3075);
WIRE 16 -1 (1750 2925)(1850 2925);
WIRE 16 -1 (1750 2825)(1850 2825);
WIRE 16 -1 (1750 2725)(1850 2725);
WIRE 16 -1 (1750 2625)(1850 2625);
WIRE 16 -1 (1750 2525)(1850 2525);
WIRE 16 -1 (1750 2425)(1850 2425);
WIRE 16 -1 (1750 2325)(1850 2325);
WIRE 16 -1 (1750 2225)(1850 2225);
WIRE 16 -1 (1750 2125)(1850 2125);
WIRE 16 -1 (1750 2025)(1850 2025);
WIRE 16 -1 (-2450 1975)(-2275 1975);
WIRE 16 -1 (3825 3975)(3575 3975);
WIRE 16 -1 (3575 3975)(3575 3925);
WIRE 16 -1 (3575 3925)(3825 3925);
WIRE 16 -1 (3575 3925)(3575 3875);
WIRE 16 -1 (3825 3875)(3575 3875);
WIRE 16 -1 (-1075 3975)(-900 3975);
WIRE 16 -1 (-1075 3825)(-900 3825);
WIRE 16 -1 (-1075 3375)(-900 3375);
WIRE 16 -1 (-1075 2625)(-900 2625);
WIRE 16 -1 (-2450 2525)(-2275 2525);
WIRE 16 -1 (-1075 2875)(-900 2875);
WIRE 16 -1 (3575 725)(3825 725);
WIRE 16 -1 (3575 725)(3575 775);
WIRE 16 -1 (3575 775)(3825 775);
WIRE 16 -1 (3575 775)(3575 825);
WIRE 16 -1 (3575 825)(3825 825);
WIRE 16 -1 (3575 825)(3575 875);
WIRE 16 -1 (3575 875)(3825 875);
WIRE 16 -1 (3575 875)(3575 925);
WIRE 16 -1 (3575 925)(3825 925);
WIRE 16 -1 (3575 925)(3575 975);
WIRE 16 -1 (3575 975)(3825 975);
WIRE 16 -1 (3575 975)(3575 1025);
WIRE 16 -1 (3575 1025)(3825 1025);
WIRE 16 -1 (3575 1025)(3575 1075);
WIRE 16 -1 (3575 1075)(3825 1075);
WIRE 16 -1 (3575 1075)(3575 1125);
WIRE 16 -1 (3575 1125)(3825 1125);
WIRE 16 -1 (3575 1125)(3575 1175);
WIRE 16 -1 (3575 1175)(3825 1175);
WIRE 16 -1 (3575 1175)(3575 1225);
WIRE 16 -1 (3825 1225)(3575 1225);
WIRE 16 -1 (3575 1225)(3575 1275);
WIRE 16 -1 (3575 1275)(3825 1275);
WIRE 16 -1 (3575 1275)(3575 1325);
WIRE 16 -1 (3575 1325)(3825 1325);
WIRE 16 -1 (3575 1325)(3575 1375);
WIRE 16 -1 (3575 1375)(3825 1375);
WIRE 16 -1 (3575 1375)(3575 1425);
WIRE 16 -1 (3575 1425)(3825 1425);
WIRE 16 -1 (3575 1425)(3575 1475);
WIRE 16 -1 (3575 1475)(3825 1475);
WIRE 16 -1 (3575 1475)(3575 1525);
WIRE 16 -1 (3575 1525)(3825 1525);
WIRE 16 -1 (3575 1525)(3575 1575);
WIRE 16 -1 (3575 1575)(3825 1575);
WIRE 16 -1 (3575 1575)(3575 1625);
WIRE 16 -1 (3575 1625)(3825 1625);
WIRE 16 -1 (3575 1625)(3575 1675);
WIRE 16 -1 (3575 1675)(3825 1675);
WIRE 16 -1 (3575 1675)(3575 1725);
WIRE 16 -1 (3825 1725)(3575 1725);
WIRE 16 -1 (3575 1725)(3575 1775);
WIRE 16 -1 (3575 1775)(3825 1775);
WIRE 16 -1 (3575 1775)(3575 1825);
WIRE 16 -1 (3575 1825)(3825 1825);
WIRE 16 -1 (3575 1825)(3575 1875);
WIRE 16 -1 (3575 1875)(3825 1875);
WIRE 16 -1 (3575 1875)(3575 1925);
WIRE 16 -1 (3575 1925)(3825 1925);
WIRE 16 -1 (3575 1925)(3575 1975);
WIRE 16 -1 (3575 1975)(3825 1975);
WIRE 16 -1 (3575 1975)(3575 2025);
WIRE 16 -1 (3575 2025)(3825 2025);
WIRE 16 -1 (3575 2025)(3575 2075);
WIRE 16 -1 (3575 2075)(3825 2075);
WIRE 16 -1 (3575 2075)(3575 2125);
WIRE 16 -1 (3575 2125)(3825 2125);
WIRE 16 -1 (3575 2125)(3575 2175);
WIRE 16 -1 (3575 2175)(3825 2175);
WIRE 16 -1 (3575 2175)(3575 2225);
WIRE 16 -1 (3825 2225)(3575 2225);
WIRE 16 -1 (3575 2225)(3575 2275);
WIRE 16 -1 (3575 2275)(3825 2275);
WIRE 16 -1 (3575 2275)(3575 2325);
WIRE 16 -1 (3575 2325)(3825 2325);
WIRE 16 -1 (3575 2325)(3575 2375);
WIRE 16 -1 (3575 2375)(3825 2375);
WIRE 16 -1 (3575 2375)(3575 2425);
WIRE 16 -1 (3575 2425)(3825 2425);
WIRE 16 -1 (3575 2425)(3575 2475);
WIRE 16 -1 (3575 2475)(3825 2475);
WIRE 16 -1 (3575 2475)(3575 2525);
WIRE 16 -1 (3575 2525)(3825 2525);
WIRE 16 -1 (3575 2525)(3575 2575);
WIRE 16 -1 (3575 2575)(3825 2575);
WIRE 16 -1 (3575 2575)(3575 2625);
WIRE 16 -1 (3575 2625)(3825 2625);
WIRE 16 -1 (3575 2625)(3575 2675);
WIRE 16 -1 (3575 2675)(3825 2675);
WIRE 16 -1 (3575 2675)(3575 2725);
WIRE 16 -1 (3825 2725)(3575 2725);
WIRE 16 -1 (3575 2725)(3575 2775);
WIRE 16 -1 (3575 2775)(3825 2775);
WIRE 16 -1 (3575 2775)(3575 2825);
WIRE 16 -1 (3575 2825)(3825 2825);
WIRE 16 -1 (3575 2825)(3575 2875);
WIRE 16 -1 (3575 2875)(3825 2875);
WIRE 16 -1 (3575 2875)(3575 2925);
WIRE 16 -1 (3575 2925)(3825 2925);
WIRE 16 -1 (3575 2925)(3575 2975);
WIRE 16 -1 (3575 2975)(3825 2975);
WIRE 16 -1 (3575 2975)(3575 3025);
WIRE 16 -1 (3575 3025)(3825 3025);
WIRE 16 -1 (3575 3025)(3575 3075);
WIRE 16 -1 (3575 3075)(3825 3075);
WIRE 16 -1 (3575 3075)(3575 3125);
WIRE 16 -1 (3575 3125)(3825 3125);
WIRE 16 -1 (3575 3125)(3575 3175);
WIRE 16 -1 (3575 3175)(3825 3175);
WIRE 16 -1 (3575 3175)(3575 3225);
WIRE 16 -1 (3825 3225)(3575 3225);
WIRE 16 -1 (3575 3225)(3575 3275);
WIRE 16 -1 (3575 3275)(3825 3275);
WIRE 16 -1 (3575 3275)(3575 3325);
WIRE 16 -1 (3575 3325)(3825 3325);
WIRE 16 -1 (3575 3325)(3575 3375);
WIRE 16 -1 (3575 3375)(3825 3375);
WIRE 16 -1 (3575 3375)(3575 3425);
WIRE 16 -1 (3575 3425)(3825 3425);
WIRE 16 -1 (3575 3425)(3575 3475);
WIRE 16 -1 (3575 3475)(3825 3475);
WIRE 16 -1 (3575 3475)(3575 3525);
WIRE 16 -1 (3575 3525)(3825 3525);
WIRE 16 -1 (3575 3525)(3575 3575);
WIRE 16 -1 (3575 3575)(3825 3575);
WIRE 16 -1 (3575 3575)(3575 3625);
WIRE 16 -1 (3575 3625)(3825 3625);
WIRE 16 -1 (3575 3625)(3575 3675);
WIRE 16 -1 (3575 3675)(3825 3675);
WIRE 16 -1 (3575 3675)(3575 3725);
WIRE 16 -1 (3825 3725)(3575 3725);
WIRE 16 -1 (3575 3725)(3575 3775);
WIRE 16 -1 (3575 3775)(3825 3775);
WIRE 16 -1 (3575 3775)(3575 3825);
WIRE 16 -1 (3825 3825)(3575 3825);
WIRE 16 -1 (-1075 2925)(-900 2925);
WIRE 16 -1 (-1075 3125)(-900 3125);
WIRE 16 -1 (-1075 3075)(-900 3075);
WIRE 16 -1 (-1075 2575)(-900 2575);
WIRE 16 -1 (-1075 2525)(-900 2525);
WIRE 16 -1 (-1075 2475)(-900 2475);
WIRE 16 -1 (5025 3975)(5275 3975);
WIRE 16 -1 (5025 3925)(5275 3925);
WIRE 16 -1 (5275 3975)(5275 3925);
WIRE 16 -1 (5025 3875)(5275 3875);
WIRE 16 -1 (5275 3925)(5275 3875);
WIRE 16 -1 (5025 3825)(5275 3825);
WIRE 16 -1 (5275 3875)(5275 3825);
WIRE 16 -1 (5025 3775)(5275 3775);
WIRE 16 -1 (5275 3825)(5275 3775);
WIRE 16 -1 (5025 3725)(5275 3725);
WIRE 16 -1 (5275 3775)(5275 3725);
WIRE 16 -1 (5025 3675)(5275 3675);
WIRE 16 -1 (5275 3725)(5275 3675);
WIRE 16 -1 (5025 3625)(5275 3625);
WIRE 16 -1 (5275 3675)(5275 3625);
WIRE 16 -1 (5025 3575)(5275 3575);
WIRE 16 -1 (5275 3625)(5275 3575);
WIRE 16 -1 (5025 3525)(5275 3525);
WIRE 16 -1 (5275 3575)(5275 3525);
WIRE 16 -1 (5025 3475)(5275 3475);
WIRE 16 -1 (5275 3525)(5275 3475);
WIRE 16 -1 (5025 3425)(5275 3425);
WIRE 16 -1 (5275 3475)(5275 3425);
WIRE 16 -1 (5025 3375)(5275 3375);
WIRE 16 -1 (5275 3425)(5275 3375);
WIRE 16 -1 (5025 3325)(5275 3325);
WIRE 16 -1 (5275 3375)(5275 3325);
WIRE 16 -1 (5025 3275)(5275 3275);
WIRE 16 -1 (5275 3325)(5275 3275);
WIRE 16 -1 (5025 3225)(5275 3225);
WIRE 16 -1 (5275 3225)(5275 3275);
WIRE 16 -1 (5025 3175)(5275 3175);
WIRE 16 -1 (5275 3225)(5275 3175);
WIRE 16 -1 (5275 3125)(5025 3125);
WIRE 16 -1 (5275 3175)(5275 3125);
WIRE 16 -1 (5275 3075)(5025 3075);
WIRE 16 -1 (5275 3125)(5275 3075);
WIRE 16 -1 (5025 3025)(5275 3025);
WIRE 16 -1 (5275 3075)(5275 3025);
WIRE 16 -1 (5025 2975)(5275 2975);
WIRE 16 -1 (5275 3025)(5275 2975);
WIRE 16 -1 (5025 2925)(5275 2925);
WIRE 16 -1 (5275 2975)(5275 2925);
WIRE 16 -1 (5025 2875)(5275 2875);
WIRE 16 -1 (5275 2925)(5275 2875);
WIRE 16 -1 (5025 2825)(5275 2825);
WIRE 16 -1 (5275 2875)(5275 2825);
WIRE 16 -1 (5025 2775)(5275 2775);
WIRE 16 -1 (5275 2825)(5275 2775);
WIRE 16 -1 (5025 2725)(5275 2725);
WIRE 16 -1 (5275 2725)(5275 2775);
WIRE 16 -1 (5025 2675)(5275 2675);
WIRE 16 -1 (5275 2725)(5275 2675);
WIRE 16 -1 (5275 2625)(5025 2625);
WIRE 16 -1 (5275 2675)(5275 2625);
WIRE 16 -1 (5275 2575)(5025 2575);
WIRE 16 -1 (5275 2625)(5275 2575);
WIRE 16 -1 (5025 2525)(5275 2525);
WIRE 16 -1 (5275 2575)(5275 2525);
WIRE 16 -1 (5025 2475)(5275 2475);
WIRE 16 -1 (5275 2525)(5275 2475);
WIRE 16 -1 (5025 2425)(5275 2425);
WIRE 16 -1 (5275 2475)(5275 2425);
WIRE 16 -1 (5025 2375)(5275 2375);
WIRE 16 -1 (5275 2425)(5275 2375);
WIRE 16 -1 (5025 2325)(5275 2325);
WIRE 16 -1 (5275 2375)(5275 2325);
WIRE 16 -1 (5025 2275)(5275 2275);
WIRE 16 -1 (5275 2325)(5275 2275);
WIRE 16 -1 (5025 2225)(5275 2225);
WIRE 16 -1 (5275 2225)(5275 2275);
WIRE 16 -1 (5025 2175)(5275 2175);
WIRE 16 -1 (5275 2225)(5275 2175);
WIRE 16 -1 (5275 2125)(5025 2125);
WIRE 16 -1 (5275 2175)(5275 2125);
WIRE 16 -1 (5275 2075)(5025 2075);
WIRE 16 -1 (5275 2125)(5275 2075);
WIRE 16 -1 (5025 2025)(5275 2025);
WIRE 16 -1 (5275 2075)(5275 2025);
WIRE 16 -1 (5025 1975)(5275 1975);
WIRE 16 -1 (5275 2025)(5275 1975);
WIRE 16 -1 (5025 1925)(5275 1925);
WIRE 16 -1 (5275 1975)(5275 1925);
WIRE 16 -1 (5025 1875)(5275 1875);
WIRE 16 -1 (5275 1925)(5275 1875);
WIRE 16 -1 (5025 1825)(5275 1825);
WIRE 16 -1 (5275 1875)(5275 1825);
WIRE 16 -1 (5025 1775)(5275 1775);
WIRE 16 -1 (5275 1825)(5275 1775);
WIRE 16 -1 (5025 1725)(5275 1725);
WIRE 16 -1 (5275 1725)(5275 1775);
WIRE 16 -1 (5025 1675)(5275 1675);
WIRE 16 -1 (5275 1725)(5275 1675);
WIRE 16 -1 (5275 1625)(5025 1625);
WIRE 16 -1 (5275 1675)(5275 1625);
WIRE 16 -1 (5275 1575)(5025 1575);
WIRE 16 -1 (5275 1625)(5275 1575);
WIRE 16 -1 (5275 1525)(5025 1525);
WIRE 16 -1 (5275 1575)(5275 1525);
WIRE 16 -1 (5275 1475)(5025 1475);
WIRE 16 -1 (5275 1525)(5275 1475);
WIRE 16 -1 (5025 1425)(5275 1425);
WIRE 16 -1 (5275 1425)(5275 1475);
WIRE 16 -1 (5275 1375)(5025 1375);
WIRE 16 -1 (5275 1375)(5275 1425);
WIRE 16 -1 (5275 1325)(5025 1325);
WIRE 16 -1 (5275 1375)(5275 1325);
WIRE 16 -1 (5275 1275)(5025 1275);
WIRE 16 -1 (5275 1325)(5275 1275);
WIRE 16 -1 (5025 1225)(5275 1225);
WIRE 16 -1 (5275 1275)(5275 1225);
WIRE 16 -1 (5025 1175)(5275 1175);
WIRE 16 -1 (5275 1225)(5275 1175);
WIRE 16 -1 (5025 1125)(5275 1125);
WIRE 16 -1 (5275 1175)(5275 1125);
WIRE 16 -1 (5025 1075)(5275 1075);
WIRE 16 -1 (5275 1125)(5275 1075);
WIRE 16 -1 (5025 1025)(5275 1025);
WIRE 16 -1 (5275 1075)(5275 1025);
WIRE 16 -1 (5025 975)(5275 975);
WIRE 16 -1 (5275 1025)(5275 975);
WIRE 16 -1 (5025 925)(5275 925);
WIRE 16 -1 (5275 975)(5275 925);
WIRE 16 -1 (5025 875)(5275 875);
WIRE 16 -1 (5275 875)(5275 925);
WIRE 16 -1 (5025 825)(5275 825);
WIRE 16 -1 (5275 875)(5275 825);
WIRE 16 -1 (5025 725)(5275 725);
WIRE 16 -1 (5275 825)(5275 725);
WIRE 16 -1 (5275 725)(5275 675);
WIRE 16 -1 (5025 675)(5275 675);
WIRE 16 -1 (-1075 2275)(-900 2275);
WIRE 16 -1 (-2275 725)(-3375 725);
FORCEPROP 2 LAST SIG_NAME TP_CHH_CPU0_DIMM1_FRU_0
J 0
(-3287 734);
DISPLAY 0.680851 (-3287 734);
PAINT WHITE (-3287 734);
WIRE 16 -1 (-2275 775)(-3375 775);
FORCEPROP 2 LAST SIG_NAME TP_CHH_CPU0_DIMM1_FRU_1
J 0
(-3287 784);
DISPLAY 0.680851 (-3287 784);
PAINT WHITE (-3287 784);
WIRE 16 -1 (-2275 825)(-3375 825);
FORCEPROP 2 LAST SIG_NAME TP_CHH_CPU0_DIMM1_FRU_2
J 0
(-3287 834);
DISPLAY 0.680851 (-3287 834);
PAINT WHITE (-3287 834);
WIRE 16 -1 (-2275 875)(-3375 875);
FORCEPROP 2 LAST SIG_NAME TP_CHH_CPU0_DIMM1_FRU_3
J 0
(-3287 884);
DISPLAY 0.680851 (-3287 884);
PAINT WHITE (-3287 884);
WIRE 16 -1 (-2275 925)(-3375 925);
FORCEPROP 2 LAST SIG_NAME TP_CHH_CPU0_DIMM1_FRU_4
J 0
(-3287 934);
DISPLAY 0.680851 (-3287 934);
PAINT WHITE (-3287 934);
WIRE 16 -1 (-2275 975)(-3375 975);
FORCEPROP 2 LAST SIG_NAME TP_CHH_CPU0_DIMM1_FRU_5
J 0
(-3287 984);
DISPLAY 0.680851 (-3287 984);
PAINT WHITE (-3287 984);
WIRE 16 -1 (-2275 3125)(-3375 3125);
FORCEPROP 2 LAST SIG_NAME M_H_CPU0_SB_PAR
J 0
(-3287 3134);
DISPLAY 0.680851 (-3287 3134);
PAINT WHITE (-3287 3134);
WIRE 16 -1 (-2275 3175)(-3375 3175);
FORCEPROP 2 LAST SIG_NAME M_H_CPU0_SA_PAR
J 0
(-3287 3184);
DISPLAY 0.680851 (-3287 3184);
PAINT WHITE (-3287 3184);
WIRE 16 -1 (-2275 525)(-3375 525);
FORCEPROP 2 LAST SIG_NAME M_H_CPU0_SB_RSP<0>
J 0
(-3287 534);
DISPLAY 0.680851 (-3287 534);
PAINT WHITE (-3287 534);
WIRE 16 -1 (-2275 575)(-3375 575);
FORCEPROP 2 LAST SIG_NAME M_H_CPU0_SA_RSP<0>
J 0
(-3287 584);
DISPLAY 0.680851 (-3287 584);
PAINT WHITE (-3287 584);
WIRE 16 -1 (-1075 775)(-900 775);
WIRE 16 -1 (-1075 825)(-900 825);
WIRE 16 -1 (-1075 875)(-900 875);
WIRE 16 -1 (-1075 925)(-900 925);
WIRE 16 -1 (-1075 975)(-900 975);
WIRE 16 -1 (-1075 1025)(-900 1025);
WIRE 16 -1 (-1075 1075)(-900 1075);
WIRE 16 -1 (-1075 1125)(-900 1125);
WIRE 16 -1 (-1075 1175)(-900 1175);
WIRE 16 -1 (-1075 1225)(-900 1225);
WIRE 16 -1 (-1075 1275)(-900 1275);
WIRE 16 -1 (-1075 1325)(-900 1325);
WIRE 16 -1 (-1075 1375)(-900 1375);
WIRE 16 -1 (-1075 1425)(-900 1425);
WIRE 16 -1 (-1075 1475)(-900 1475);
WIRE 16 -1 (-1075 1525)(-900 1525);
WIRE 16 -1 (-1075 1575)(-900 1575);
WIRE 16 -1 (-1075 1625)(-900 1625);
WIRE 16 -1 (-1075 1675)(-900 1675);
WIRE 16 -1 (-1075 1725)(-900 1725);
WIRE 16 -1 (-1075 1775)(-900 1775);
WIRE 16 -1 (-1075 1825)(-900 1825);
WIRE 16 -1 (-1075 1875)(-900 1875);
WIRE 16 -1 (-1075 1925)(-900 1925);
WIRE 16 -1 (-1075 1975)(-900 1975);
WIRE 16 -1 (-1075 2025)(-900 2025);
WIRE 16 -1 (-1075 2075)(-900 2075);
WIRE 16 -1 (-1075 2125)(-900 2125);
WIRE 16 -1 (-1075 2175)(-900 2175);
WIRE 16 -1 (-1075 2325)(-900 2325);
WIRE 16 -1 (-1075 2425)(-900 2425);
WIRE 16 -1 (-1075 2675)(-900 2675);
WIRE 16 -1 (-1075 2725)(-900 2725);
WIRE 16 -1 (-1075 2775)(-900 2775);
WIRE 16 -1 (-1075 2825)(-900 2825);
WIRE 16 -1 (-1075 2975)(-900 2975);
WIRE 16 -1 (-1075 3025)(-900 3025);
WIRE 16 -1 (-1075 3175)(-900 3175);
WIRE 16 -1 (-1075 3225)(-900 3225);
WIRE 16 -1 (-1075 3275)(-900 3275);
WIRE 16 -1 (-1075 3325)(-900 3325);
WIRE 16 -1 (-1075 3425)(-900 3425);
WIRE 16 -1 (-1075 3475)(-900 3475);
WIRE 16 -1 (-1075 3525)(-900 3525);
WIRE 16 -1 (-1075 3575)(-900 3575);
WIRE 16 -1 (-1075 3625)(-900 3625);
WIRE 16 -1 (-1075 3675)(-900 3675);
WIRE 16 -1 (-1075 3725)(-900 3725);
WIRE 16 -1 (-1075 3775)(-900 3775);
WIRE 16 -1 (-1075 3875)(-900 3875);
WIRE 16 -1 (-1075 3925)(-900 3925);
WIRE 16 -1 (-2275 2875)(-3375 2875);
FORCEPROP 2 LAST SIG_NAME M_H_CPU0_SB_CS_N<1>
J 0
(-3287 2884);
DISPLAY 0.680851 (-3287 2884);
PAINT WHITE (-3287 2884);
WIRE 16 -1 (-2275 3025)(-3375 3025);
FORCEPROP 2 LAST SIG_NAME M_H_CPU0_SA_CS_N<1>
J 0
(-3287 3034);
DISPLAY 0.680851 (-3287 3034);
PAINT WHITE (-3287 3034);
WIRE 16 -1 (-2275 2825)(-3375 2825);
FORCEPROP 2 LAST SIG_NAME M_H_CPU0_SB_CS_N<0>
J 0
(-3287 2834);
DISPLAY 0.680851 (-3287 2834);
PAINT WHITE (-3287 2834);
WIRE 16 -1 (-2275 2975)(-3375 2975);
FORCEPROP 2 LAST SIG_NAME M_H_CPU0_SA_CS_N<0>
J 0
(-3287 2984);
DISPLAY 0.680851 (-3287 2984);
PAINT WHITE (-3287 2984);
WIRE 16 -1 (-2275 2725)(-3375 2725);
FORCEPROP 2 LAST SIG_NAME M_H_CPU0_CLK_DP<0>
J 0
(-3287 2734);
DISPLAY 0.680851 (-3287 2734);
PAINT WHITE (-3287 2734);
WIRE 16 -1 (-2450 1775)(-2275 1775);
WIRE 16 -1 (-2450 1875)(-2275 1875);
WIRE 16 -1 (-2450 1925)(-2275 1925);
WIRE 16 -1 (-2450 2025)(-2275 2025);
WIRE 16 -1 (-2450 2075)(-2275 2075);
WIRE 16 -1 (-2450 2225)(-2275 2225);
WIRE 16 -1 (-2450 2325)(-2275 2325);
WIRE 16 -1 (-2450 2375)(-2275 2375);
WIRE 16 -1 (-2450 2475)(-2275 2475);
WIRE 16 -1 (-2450 3575)(-2275 3575);
WIRE 16 -1 (-2450 3975)(-2275 3975);
WIRE 16 -1 (-2450 3525)(-2275 3525);
WIRE 16 -1 (-2450 3925)(-2275 3925);
WIRE 16 -1 (-2450 3475)(-2275 3475);
WIRE 16 -1 (-2450 3875)(-2275 3875);
WIRE 16 -1 (-2450 3425)(-2275 3425);
WIRE 16 -1 (-2450 3825)(-2275 3825);
WIRE 16 -1 (-2450 3375)(-2275 3375);
WIRE 16 -1 (-2450 3775)(-2275 3775);
WIRE 16 -1 (-2450 3325)(-2275 3325);
WIRE 16 -1 (-2450 3725)(-2275 3725);
WIRE 16 -1 (-2450 3275)(-2275 3275);
WIRE 16 -1 (-2450 3675)(-2275 3675);
WIRE 16 -1 (-2450 2125)(-2275 2125);
WIRE 16 -1 (-2450 2275)(-2275 2275);
WIRE 16 -1 (-2450 2425)(-2275 2425);
WIRE 16 -1 (-2450 2575)(-2275 2575);
WIRE 16 -1 (-2275 -75)(-2275 25);
WIRE 16 -1 (-2275 25)(-3375 25);
FORCEPROP 2 LAST SIG_NAME PD_CHH_CPU0_DIMM1_SAA
J 0
(-3287 34);
DISPLAY 0.680851 (-3287 34);
PAINT WHITE (-3287 34);
WIRE 16 -1 (1875 325)(1875 200);
WIRE 16 -1 (2500 325)(1875 325);
WIRE 16 -1 (2500 200)(2500 325);
WIRE 16 -1 (2500 -150)(2500 0);
WIRE 16 -1 (2500 -150)(1875 -150);
WIRE 16 -1 (1875 -150)(1875 0);
DOT 1 (3575 3225);
DOT 1 (3575 3125);
DOT 1 (3575 2275);
DOT 1 (3575 2075);
DOT 1 (2500 -150);
DOT 1 (1875 325);
DOT 1 (3575 725);
DOT 1 (3575 775);
DOT 1 (3575 825);
DOT 1 (3575 875);
DOT 1 (3575 925);
DOT 1 (3575 975);
DOT 1 (3575 1025);
DOT 1 (3575 1075);
DOT 1 (3575 1125);
DOT 1 (3575 1175);
DOT 1 (3575 1225);
DOT 1 (3575 1275);
DOT 1 (3575 1325);
DOT 1 (3575 1375);
DOT 1 (3575 1425);
DOT 1 (3575 1475);
DOT 1 (3575 1525);
DOT 1 (3575 1575);
DOT 1 (3575 1625);
DOT 1 (3575 1675);
DOT 1 (3575 1725);
DOT 1 (3575 1775);
DOT 1 (3575 1825);
DOT 1 (3575 1875);
DOT 1 (3575 1925);
DOT 1 (3575 1975);
DOT 1 (3575 2025);
DOT 1 (3575 2125);
DOT 1 (3575 2175);
DOT 1 (3575 2225);
DOT 1 (3575 2325);
DOT 1 (3575 2375);
DOT 1 (3575 2425);
DOT 1 (3575 2475);
DOT 1 (3575 2525);
DOT 1 (3575 2675);
DOT 1 (3575 2625);
DOT 1 (3575 2575);
DOT 1 (3575 2775);
DOT 1 (3575 2725);
DOT 1 (3575 2825);
DOT 1 (3575 2875);
DOT 1 (3575 2925);
DOT 1 (3575 2975);
DOT 1 (3575 3025);
DOT 1 (3575 3075);
DOT 1 (3575 3175);
DOT 1 (3575 3275);
DOT 1 (3575 3325);
DOT 1 (3575 3375);
DOT 1 (3575 3425);
DOT 1 (3575 3475);
DOT 1 (3575 3525);
DOT 1 (3575 3575);
DOT 1 (3575 3675);
DOT 1 (3575 3625);
DOT 1 (3575 3725);
DOT 1 (3575 3775);
DOT 1 (3575 3925);
DOT 1 (3575 3975);
DOT 1 (5275 825);
DOT 1 (5275 875);
DOT 1 (5275 925);
DOT 1 (5275 975);
DOT 1 (5275 1025);
DOT 1 (5275 1075);
DOT 1 (5275 1125);
DOT 1 (5275 1175);
DOT 1 (5275 1225);
DOT 1 (5275 1275);
DOT 1 (5275 1325);
DOT 1 (5275 1375);
DOT 1 (5275 1425);
DOT 1 (5275 1475);
DOT 1 (5275 1525);
DOT 1 (5275 1575);
DOT 1 (5275 1625);
DOT 1 (5275 1675);
DOT 1 (5275 1725);
DOT 1 (5275 1775);
DOT 1 (5275 1825);
DOT 1 (5275 1875);
DOT 1 (5275 1925);
DOT 1 (5275 1975);
DOT 1 (5275 2025);
DOT 1 (5275 2075);
DOT 1 (5275 2125);
DOT 1 (5275 2175);
DOT 1 (5275 2275);
DOT 1 (5275 2225);
DOT 1 (5275 2325);
DOT 1 (5275 2375);
DOT 1 (5275 2425);
DOT 1 (5275 2475);
DOT 1 (5275 2525);
DOT 1 (5275 2575);
DOT 1 (5275 2625);
DOT 1 (5275 2675);
DOT 1 (5275 2725);
DOT 1 (5275 2775);
DOT 1 (5275 2825);
DOT 1 (5275 2875);
DOT 1 (5275 2925);
DOT 1 (5275 2975);
DOT 1 (5275 3025);
DOT 1 (5275 3075);
DOT 1 (5275 3125);
DOT 1 (5275 3175);
DOT 1 (5275 3225);
DOT 1 (5275 3275);
DOT 1 (5275 3325);
DOT 1 (5275 3375);
DOT 1 (5275 3425);
DOT 1 (5275 3475);
DOT 1 (5275 3525);
DOT 1 (5275 3575);
DOT 1 (5275 3625);
DOT 1 (5275 3675);
DOT 1 (5275 3725);
DOT 1 (5275 3775);
DOT 1 (5275 3825);
DOT 1 (5275 3875);
DOT 1 (5275 3925);
DOT 1 (5275 725);
DOT 1 (5275 675);
DOT 1 (5275 625);
FORCENOTE
20210728 MODIFY FOR GT
(-3775 4650) 0;
DISPLAY LEFT (-3775 4650);
DISPLAY 2.510638 (-3775 4650);
PAINT PINK (-3775 4650);
QUIT
